FILE_TYPE = MACRO_DRAWING;
SET COLOR_WIRE YELLOW;
SET COLOR_PROP MONO;
SET COLOR_DOT WHITE;
SET COLOR_ARC YELLOW;
SET COLOR_BODY GREEN;
SET COLOR_NOTE MONO;
SET PROP_DISPLAY VALUE;
SET PAGE_NUMBER P32;
FORCEADD OFFPAGE..1
(-7275 3500);
FORCEPROP 2 LAST $XR1 187 
J 0
(-7677 3500);
DISPLAY 0.638298 (-7677 3500);
PAINT MONO (-7677 3500);
FORCEPROP 2 LAST $XR0 186 
J 0
(-7557 3500);
DISPLAY 0.638298 (-7557 3500);
PAINT MONO (-7557 3500);
FORCEPROP 2 LAST CDS_LIB mstr_standard
J 0
(-7275 3500);
PAINT MONO (-7275 3500);
DISPLAY INVISIBLE (-7275 3500);
FORCEPROP 1 LAST OFFPAGE TRUE
J 0
(-6950 3375);
DISPLAY 1.170213 (-6950 3375);
PAINT GREEN (-6950 3375);
DISPLAY INVISIBLE (-6950 3375);
FORCEPROP 1 LAST COMMENT_BODY TRUE
J 0
(-7150 3400);
DISPLAY 1.170213 (-7150 3400);
PAINT GREEN (-7150 3400);
DISPLAY INVISIBLE (-7150 3400);
FORCEPROP 2 LAST PATH I1
J 0
(-7225 3575);
DISPLAY 1.021277 (-7225 3575);
PAINT ORANGE (-7225 3575);
DISPLAY INVISIBLE (-7225 3575);
FORCEADD TAP..1
R 2
(-5875 2025);
FORCEPROP 3 LASTPIN (-5825 2025) SIG_NAME P3E_CPU0_PE3_OCP_RXP<3>
J 0
(-5815 2035);
DISPLAY 0.659574 (-5815 2035);
PAINT MONO (-5815 2035);
DISPLAY INVISIBLE (-5815 2035);
FORCEPROP 1 LASTPIN (-5825 2025) BN 3
J 2
(-5813 2033);
DISPLAY 0.617021 (-5813 2033);
PAINT PINK (-5813 2033);
FORCEPROP 2 LAST CDS_LIB mstr_standard
J 0
(-5875 2025);
PAINT MONO (-5875 2025);
DISPLAY INVISIBLE (-5875 2025);
FORCEPROP 1 LAST BODY_TYPE PLUMBING
J 2
(-5875 2075);
DISPLAY 1.446809 (-5875 2075);
PAINT GREEN (-5875 2075);
DISPLAY INVISIBLE (-5875 2075);
FORCEPROP 1 LAST HDL_TAP TRUE
J 2
(-6200 1900);
DISPLAY 1.446809 (-6200 1900);
PAINT GREEN (-6200 1900);
DISPLAY INVISIBLE (-6200 1900);
FORCEPROP 1 LAST PATH I15
J 2
(-5873 2025);
DISPLAY 0.872340 (-5873 2025);
PAINT GREEN (-5873 2025);
DISPLAY INVISIBLE (-5873 2025);
FORCEADD OFFPAGE..1
(-7275 3625);
FORCEPROP 2 LAST $XR1 187 
J 0
(-7677 3625);
DISPLAY 0.638298 (-7677 3625);
PAINT MONO (-7677 3625);
FORCEPROP 2 LAST $XR0 186 
J 0
(-7557 3625);
DISPLAY 0.638298 (-7557 3625);
PAINT MONO (-7557 3625);
FORCEPROP 2 LAST CDS_LIB mstr_standard
J 0
(-7275 3625);
PAINT MONO (-7275 3625);
DISPLAY INVISIBLE (-7275 3625);
FORCEPROP 1 LAST OFFPAGE TRUE
J 0
(-6950 3500);
DISPLAY 1.170213 (-6950 3500);
PAINT GREEN (-6950 3500);
DISPLAY INVISIBLE (-6950 3500);
FORCEPROP 1 LAST COMMENT_BODY TRUE
J 0
(-7150 3525);
DISPLAY 1.170213 (-7150 3525);
PAINT GREEN (-7150 3525);
DISPLAY INVISIBLE (-7150 3525);
FORCEPROP 2 LAST PATH I2
J 0
(-7225 3700);
DISPLAY 1.021277 (-7225 3700);
PAINT ORANGE (-7225 3700);
DISPLAY INVISIBLE (-7225 3700);
FORCEADD TAP..1
R 2
(-6025 2625);
FORCEPROP 3 LASTPIN (-5975 2625) SIG_NAME P3E_CPU0_PE3_OCP_RXN<8>
J 0
(-5965 2635);
DISPLAY 0.659574 (-5965 2635);
PAINT MONO (-5965 2635);
DISPLAY INVISIBLE (-5965 2635);
FORCEPROP 1 LASTPIN (-5975 2625) BN 8
J 2
(-5963 2633);
DISPLAY 0.617021 (-5963 2633);
PAINT PINK (-5963 2633);
FORCEPROP 2 LAST CDS_LIB mstr_standard
J 0
(-6025 2625);
PAINT MONO (-6025 2625);
DISPLAY INVISIBLE (-6025 2625);
FORCEPROP 1 LAST BODY_TYPE PLUMBING
J 2
(-6025 2675);
DISPLAY 1.446809 (-6025 2675);
PAINT GREEN (-6025 2675);
DISPLAY INVISIBLE (-6025 2675);
FORCEPROP 1 LAST HDL_TAP TRUE
J 2
(-6350 2500);
DISPLAY 1.446809 (-6350 2500);
PAINT GREEN (-6350 2500);
DISPLAY INVISIBLE (-6350 2500);
FORCEPROP 1 LAST PATH I20
J 2
(-6023 2625);
DISPLAY 0.872340 (-6023 2625);
PAINT GREEN (-6023 2625);
DISPLAY INVISIBLE (-6023 2625);
FORCEADD TAP..1
R 2
(-6025 2675);
FORCEPROP 3 LASTPIN (-5975 2675) SIG_NAME P3E_CPU0_PE3_OCP_RXN<9>
J 0
(-5965 2685);
DISPLAY 0.659574 (-5965 2685);
PAINT MONO (-5965 2685);
DISPLAY INVISIBLE (-5965 2685);
FORCEPROP 1 LASTPIN (-5975 2675) BN 9
J 2
(-5963 2683);
DISPLAY 0.617021 (-5963 2683);
PAINT PINK (-5963 2683);
FORCEPROP 2 LAST CDS_LIB mstr_standard
J 0
(-6025 2675);
PAINT MONO (-6025 2675);
DISPLAY INVISIBLE (-6025 2675);
FORCEPROP 1 LAST BODY_TYPE PLUMBING
J 2
(-6025 2725);
DISPLAY 1.446809 (-6025 2725);
PAINT GREEN (-6025 2725);
DISPLAY INVISIBLE (-6025 2725);
FORCEPROP 1 LAST HDL_TAP TRUE
J 2
(-6350 2550);
DISPLAY 1.446809 (-6350 2550);
PAINT GREEN (-6350 2550);
DISPLAY INVISIBLE (-6350 2550);
FORCEPROP 1 LAST PATH I21
J 2
(-6023 2675);
DISPLAY 0.872340 (-6023 2675);
PAINT GREEN (-6023 2675);
DISPLAY INVISIBLE (-6023 2675);
FORCEADD TAP..1
R 2
(-6025 2725);
FORCEPROP 3 LASTPIN (-5975 2725) SIG_NAME P3E_CPU0_PE3_OCP_RXN<10>
J 0
(-5965 2735);
DISPLAY 0.659574 (-5965 2735);
PAINT MONO (-5965 2735);
DISPLAY INVISIBLE (-5965 2735);
FORCEPROP 1 LASTPIN (-5975 2725) BN 10
J 2
(-5963 2733);
DISPLAY 0.617021 (-5963 2733);
PAINT PINK (-5963 2733);
FORCEPROP 2 LAST CDS_LIB mstr_standard
J 0
(-6025 2725);
PAINT MONO (-6025 2725);
DISPLAY INVISIBLE (-6025 2725);
FORCEPROP 1 LAST BODY_TYPE PLUMBING
J 2
(-6025 2775);
DISPLAY 1.446809 (-6025 2775);
PAINT GREEN (-6025 2775);
DISPLAY INVISIBLE (-6025 2775);
FORCEPROP 1 LAST HDL_TAP TRUE
J 2
(-6350 2600);
DISPLAY 1.446809 (-6350 2600);
PAINT GREEN (-6350 2600);
DISPLAY INVISIBLE (-6350 2600);
FORCEPROP 1 LAST PATH I22
J 2
(-6023 2725);
DISPLAY 0.872340 (-6023 2725);
PAINT GREEN (-6023 2725);
DISPLAY INVISIBLE (-6023 2725);
FORCEADD TAP..1
R 2
(-6025 2775);
FORCEPROP 3 LASTPIN (-5975 2775) SIG_NAME P3E_CPU0_PE3_OCP_RXN<11>
J 0
(-5965 2785);
DISPLAY 0.659574 (-5965 2785);
PAINT MONO (-5965 2785);
DISPLAY INVISIBLE (-5965 2785);
FORCEPROP 1 LASTPIN (-5975 2775) BN 11
J 2
(-5963 2783);
DISPLAY 0.617021 (-5963 2783);
PAINT PINK (-5963 2783);
FORCEPROP 2 LAST CDS_LIB mstr_standard
J 0
(-6025 2775);
PAINT MONO (-6025 2775);
DISPLAY INVISIBLE (-6025 2775);
FORCEPROP 1 LAST BODY_TYPE PLUMBING
J 2
(-6025 2825);
DISPLAY 1.446809 (-6025 2825);
PAINT GREEN (-6025 2825);
DISPLAY INVISIBLE (-6025 2825);
FORCEPROP 1 LAST HDL_TAP TRUE
J 2
(-6350 2650);
DISPLAY 1.446809 (-6350 2650);
PAINT GREEN (-6350 2650);
DISPLAY INVISIBLE (-6350 2650);
FORCEPROP 1 LAST PATH I23
J 2
(-6023 2775);
DISPLAY 0.872340 (-6023 2775);
PAINT GREEN (-6023 2775);
DISPLAY INVISIBLE (-6023 2775);
FORCEADD TAP..1
R 2
(-5875 2875);
FORCEPROP 3 LASTPIN (-5825 2875) SIG_NAME P3E_CPU0_PE3_OCP_RXP<8>
J 0
(-5815 2885);
DISPLAY 0.659574 (-5815 2885);
PAINT MONO (-5815 2885);
DISPLAY INVISIBLE (-5815 2885);
FORCEPROP 1 LASTPIN (-5825 2875) BN 8
J 2
(-5813 2883);
DISPLAY 0.617021 (-5813 2883);
PAINT PINK (-5813 2883);
FORCEPROP 2 LAST CDS_LIB mstr_standard
J 0
(-5875 2875);
PAINT MONO (-5875 2875);
DISPLAY INVISIBLE (-5875 2875);
FORCEPROP 1 LAST BODY_TYPE PLUMBING
J 2
(-5875 2925);
DISPLAY 1.446809 (-5875 2925);
PAINT GREEN (-5875 2925);
DISPLAY INVISIBLE (-5875 2925);
FORCEPROP 1 LAST HDL_TAP TRUE
J 2
(-6200 2750);
DISPLAY 1.446809 (-6200 2750);
PAINT GREEN (-6200 2750);
DISPLAY INVISIBLE (-6200 2750);
FORCEPROP 1 LAST PATH I24
J 2
(-5873 2875);
DISPLAY 0.872340 (-5873 2875);
PAINT GREEN (-5873 2875);
DISPLAY INVISIBLE (-5873 2875);
FORCEADD TAP..1
R 2
(-5875 2975);
FORCEPROP 3 LASTPIN (-5825 2975) SIG_NAME P3E_CPU0_PE3_OCP_RXP<10>
J 0
(-5815 2985);
DISPLAY 0.659574 (-5815 2985);
PAINT MONO (-5815 2985);
DISPLAY INVISIBLE (-5815 2985);
FORCEPROP 1 LASTPIN (-5825 2975) BN 10
J 2
(-5813 2983);
DISPLAY 0.617021 (-5813 2983);
PAINT PINK (-5813 2983);
FORCEPROP 2 LAST CDS_LIB mstr_standard
J 0
(-5875 2975);
PAINT MONO (-5875 2975);
DISPLAY INVISIBLE (-5875 2975);
FORCEPROP 1 LAST BODY_TYPE PLUMBING
J 2
(-5875 3025);
DISPLAY 1.446809 (-5875 3025);
PAINT GREEN (-5875 3025);
DISPLAY INVISIBLE (-5875 3025);
FORCEPROP 1 LAST HDL_TAP TRUE
J 2
(-6200 2850);
DISPLAY 1.446809 (-6200 2850);
PAINT GREEN (-6200 2850);
DISPLAY INVISIBLE (-6200 2850);
FORCEPROP 1 LAST PATH I25
J 2
(-5873 2975);
DISPLAY 0.872340 (-5873 2975);
PAINT GREEN (-5873 2975);
DISPLAY INVISIBLE (-5873 2975);
FORCEADD TAP..1
R 2
(-5875 2925);
FORCEPROP 3 LASTPIN (-5825 2925) SIG_NAME P3E_CPU0_PE3_OCP_RXP<9>
J 0
(-5815 2935);
DISPLAY 0.659574 (-5815 2935);
PAINT MONO (-5815 2935);
DISPLAY INVISIBLE (-5815 2935);
FORCEPROP 1 LASTPIN (-5825 2925) BN 9
J 2
(-5813 2933);
DISPLAY 0.617021 (-5813 2933);
PAINT PINK (-5813 2933);
FORCEPROP 2 LAST CDS_LIB mstr_standard
J 0
(-5875 2925);
PAINT MONO (-5875 2925);
DISPLAY INVISIBLE (-5875 2925);
FORCEPROP 1 LAST BODY_TYPE PLUMBING
J 2
(-5875 2975);
DISPLAY 1.446809 (-5875 2975);
PAINT GREEN (-5875 2975);
DISPLAY INVISIBLE (-5875 2975);
FORCEPROP 1 LAST HDL_TAP TRUE
J 2
(-6200 2800);
DISPLAY 1.446809 (-6200 2800);
PAINT GREEN (-6200 2800);
DISPLAY INVISIBLE (-6200 2800);
FORCEPROP 1 LAST PATH I26
J 2
(-5873 2925);
DISPLAY 0.872340 (-5873 2925);
PAINT GREEN (-5873 2925);
DISPLAY INVISIBLE (-5873 2925);
FORCEADD TAP..1
R 2
(-5875 3025);
FORCEPROP 3 LASTPIN (-5825 3025) SIG_NAME P3E_CPU0_PE3_OCP_RXP<11>
J 0
(-5815 3035);
DISPLAY 0.659574 (-5815 3035);
PAINT MONO (-5815 3035);
DISPLAY INVISIBLE (-5815 3035);
FORCEPROP 1 LASTPIN (-5825 3025) BN 11
J 2
(-5813 3033);
DISPLAY 0.617021 (-5813 3033);
PAINT PINK (-5813 3033);
FORCEPROP 2 LAST CDS_LIB mstr_standard
J 0
(-5875 3025);
PAINT MONO (-5875 3025);
DISPLAY INVISIBLE (-5875 3025);
FORCEPROP 1 LAST BODY_TYPE PLUMBING
J 2
(-5875 3075);
DISPLAY 1.446809 (-5875 3075);
PAINT GREEN (-5875 3075);
DISPLAY INVISIBLE (-5875 3075);
FORCEPROP 1 LAST HDL_TAP TRUE
J 2
(-6200 2900);
DISPLAY 1.446809 (-6200 2900);
PAINT GREEN (-6200 2900);
DISPLAY INVISIBLE (-6200 2900);
FORCEPROP 1 LAST PATH I27
J 2
(-5873 3025);
DISPLAY 0.872340 (-5873 3025);
PAINT GREEN (-5873 3025);
DISPLAY INVISIBLE (-5873 3025);
FORCEADD TAP..1
R 2
(-6025 3125);
FORCEPROP 3 LASTPIN (-5975 3125) SIG_NAME P3E_CPU0_PE3_OCP_RXN<12>
J 0
(-5965 3135);
DISPLAY 0.659574 (-5965 3135);
PAINT MONO (-5965 3135);
DISPLAY INVISIBLE (-5965 3135);
FORCEPROP 1 LASTPIN (-5975 3125) BN 12
J 2
(-5963 3133);
DISPLAY 0.617021 (-5963 3133);
PAINT PINK (-5963 3133);
FORCEPROP 2 LAST CDS_LIB mstr_standard
J 0
(-6025 3125);
PAINT MONO (-6025 3125);
DISPLAY INVISIBLE (-6025 3125);
FORCEPROP 1 LAST BODY_TYPE PLUMBING
J 2
(-6025 3175);
DISPLAY 1.446809 (-6025 3175);
PAINT GREEN (-6025 3175);
DISPLAY INVISIBLE (-6025 3175);
FORCEPROP 1 LAST HDL_TAP TRUE
J 2
(-6350 3000);
DISPLAY 1.446809 (-6350 3000);
PAINT GREEN (-6350 3000);
DISPLAY INVISIBLE (-6350 3000);
FORCEPROP 1 LAST PATH I28
J 2
(-6023 3125);
DISPLAY 0.872340 (-6023 3125);
PAINT GREEN (-6023 3125);
DISPLAY INVISIBLE (-6023 3125);
FORCEADD TAP..1
R 2
(-6025 3175);
FORCEPROP 3 LASTPIN (-5975 3175) SIG_NAME P3E_CPU0_PE3_OCP_RXN<13>
J 0
(-5965 3185);
DISPLAY 0.659574 (-5965 3185);
PAINT MONO (-5965 3185);
DISPLAY INVISIBLE (-5965 3185);
FORCEPROP 1 LASTPIN (-5975 3175) BN 13
J 2
(-5963 3183);
DISPLAY 0.617021 (-5963 3183);
PAINT PINK (-5963 3183);
FORCEPROP 2 LAST CDS_LIB mstr_standard
J 0
(-6025 3175);
PAINT MONO (-6025 3175);
DISPLAY INVISIBLE (-6025 3175);
FORCEPROP 1 LAST BODY_TYPE PLUMBING
J 2
(-6025 3225);
DISPLAY 1.446809 (-6025 3225);
PAINT GREEN (-6025 3225);
DISPLAY INVISIBLE (-6025 3225);
FORCEPROP 1 LAST HDL_TAP TRUE
J 2
(-6350 3050);
DISPLAY 1.446809 (-6350 3050);
PAINT GREEN (-6350 3050);
DISPLAY INVISIBLE (-6350 3050);
FORCEPROP 1 LAST PATH I29
J 2
(-6023 3175);
DISPLAY 0.872340 (-6023 3175);
PAINT GREEN (-6023 3175);
DISPLAY INVISIBLE (-6023 3175);
FORCEADD TAP..1
R 2
(-6025 1625);
FORCEPROP 3 LASTPIN (-5975 1625) SIG_NAME P3E_CPU0_PE3_OCP_RXN<0>
J 0
(-5965 1635);
DISPLAY 0.659574 (-5965 1635);
PAINT MONO (-5965 1635);
DISPLAY INVISIBLE (-5965 1635);
FORCEPROP 1 LASTPIN (-5975 1625) BN 0
J 2
(-5963 1633);
DISPLAY 0.617021 (-5963 1633);
PAINT PINK (-5963 1633);
FORCEPROP 2 LAST CDS_LIB mstr_standard
J 0
(-6025 1625);
PAINT MONO (-6025 1625);
DISPLAY INVISIBLE (-6025 1625);
FORCEPROP 1 LAST BODY_TYPE PLUMBING
J 2
(-6025 1675);
DISPLAY 1.446809 (-6025 1675);
PAINT GREEN (-6025 1675);
DISPLAY INVISIBLE (-6025 1675);
FORCEPROP 1 LAST HDL_TAP TRUE
J 2
(-6350 1500);
DISPLAY 1.446809 (-6350 1500);
PAINT GREEN (-6350 1500);
DISPLAY INVISIBLE (-6350 1500);
FORCEPROP 1 LAST PATH I3
J 2
(-6023 1625);
DISPLAY 0.872340 (-6023 1625);
PAINT GREEN (-6023 1625);
DISPLAY INVISIBLE (-6023 1625);
FORCEADD TAP..1
R 2
(-6025 3275);
FORCEPROP 3 LASTPIN (-5975 3275) SIG_NAME P3E_CPU0_PE3_OCP_RXN<15>
J 0
(-5965 3285);
DISPLAY 0.659574 (-5965 3285);
PAINT MONO (-5965 3285);
DISPLAY INVISIBLE (-5965 3285);
FORCEPROP 1 LASTPIN (-5975 3275) BN 15
J 2
(-5963 3283);
DISPLAY 0.617021 (-5963 3283);
PAINT PINK (-5963 3283);
FORCEPROP 2 LAST CDS_LIB mstr_standard
J 0
(-6025 3275);
PAINT MONO (-6025 3275);
DISPLAY INVISIBLE (-6025 3275);
FORCEPROP 1 LAST BODY_TYPE PLUMBING
J 2
(-6025 3325);
DISPLAY 1.446809 (-6025 3325);
PAINT GREEN (-6025 3325);
DISPLAY INVISIBLE (-6025 3325);
FORCEPROP 1 LAST HDL_TAP TRUE
J 2
(-6350 3150);
DISPLAY 1.446809 (-6350 3150);
PAINT GREEN (-6350 3150);
DISPLAY INVISIBLE (-6350 3150);
FORCEPROP 1 LAST PATH I30
J 2
(-6023 3275);
DISPLAY 0.872340 (-6023 3275);
PAINT GREEN (-6023 3275);
DISPLAY INVISIBLE (-6023 3275);
FORCEADD TAP..1
R 2
(-6025 3225);
FORCEPROP 3 LASTPIN (-5975 3225) SIG_NAME P3E_CPU0_PE3_OCP_RXN<14>
J 0
(-5965 3235);
DISPLAY 0.659574 (-5965 3235);
PAINT MONO (-5965 3235);
DISPLAY INVISIBLE (-5965 3235);
FORCEPROP 1 LASTPIN (-5975 3225) BN 14
J 2
(-5963 3233);
DISPLAY 0.617021 (-5963 3233);
PAINT PINK (-5963 3233);
FORCEPROP 2 LAST CDS_LIB mstr_standard
J 0
(-6025 3225);
PAINT MONO (-6025 3225);
DISPLAY INVISIBLE (-6025 3225);
FORCEPROP 1 LAST BODY_TYPE PLUMBING
J 2
(-6025 3275);
DISPLAY 1.446809 (-6025 3275);
PAINT GREEN (-6025 3275);
DISPLAY INVISIBLE (-6025 3275);
FORCEPROP 1 LAST HDL_TAP TRUE
J 2
(-6350 3100);
DISPLAY 1.446809 (-6350 3100);
PAINT GREEN (-6350 3100);
DISPLAY INVISIBLE (-6350 3100);
FORCEPROP 1 LAST PATH I31
J 2
(-6023 3225);
DISPLAY 0.872340 (-6023 3225);
PAINT GREEN (-6023 3225);
DISPLAY INVISIBLE (-6023 3225);
FORCEADD TAP..1
R 2
(-5875 3375);
FORCEPROP 3 LASTPIN (-5825 3375) SIG_NAME P3E_CPU0_PE3_OCP_RXP<12>
J 0
(-5815 3385);
DISPLAY 0.659574 (-5815 3385);
PAINT MONO (-5815 3385);
DISPLAY INVISIBLE (-5815 3385);
FORCEPROP 1 LASTPIN (-5825 3375) BN 12
J 2
(-5813 3383);
DISPLAY 0.617021 (-5813 3383);
PAINT PINK (-5813 3383);
FORCEPROP 2 LAST CDS_LIB mstr_standard
J 0
(-5875 3375);
PAINT MONO (-5875 3375);
DISPLAY INVISIBLE (-5875 3375);
FORCEPROP 1 LAST BODY_TYPE PLUMBING
J 2
(-5875 3425);
DISPLAY 1.446809 (-5875 3425);
PAINT GREEN (-5875 3425);
DISPLAY INVISIBLE (-5875 3425);
FORCEPROP 1 LAST HDL_TAP TRUE
J 2
(-6200 3250);
DISPLAY 1.446809 (-6200 3250);
PAINT GREEN (-6200 3250);
DISPLAY INVISIBLE (-6200 3250);
FORCEPROP 1 LAST PATH I32
J 2
(-5873 3375);
DISPLAY 0.872340 (-5873 3375);
PAINT GREEN (-5873 3375);
DISPLAY INVISIBLE (-5873 3375);
FORCEADD TAP..1
R 2
(-5875 3425);
FORCEPROP 3 LASTPIN (-5825 3425) SIG_NAME P3E_CPU0_PE3_OCP_RXP<13>
J 0
(-5815 3435);
DISPLAY 0.659574 (-5815 3435);
PAINT MONO (-5815 3435);
DISPLAY INVISIBLE (-5815 3435);
FORCEPROP 1 LASTPIN (-5825 3425) BN 13
J 2
(-5813 3433);
DISPLAY 0.617021 (-5813 3433);
PAINT PINK (-5813 3433);
FORCEPROP 2 LAST CDS_LIB mstr_standard
J 0
(-5875 3425);
PAINT MONO (-5875 3425);
DISPLAY INVISIBLE (-5875 3425);
FORCEPROP 1 LAST BODY_TYPE PLUMBING
J 2
(-5875 3475);
DISPLAY 1.446809 (-5875 3475);
PAINT GREEN (-5875 3475);
DISPLAY INVISIBLE (-5875 3475);
FORCEPROP 1 LAST HDL_TAP TRUE
J 2
(-6200 3300);
DISPLAY 1.446809 (-6200 3300);
PAINT GREEN (-6200 3300);
DISPLAY INVISIBLE (-6200 3300);
FORCEPROP 1 LAST PATH I33
J 2
(-5873 3425);
DISPLAY 0.872340 (-5873 3425);
PAINT GREEN (-5873 3425);
DISPLAY INVISIBLE (-5873 3425);
FORCEADD TAP..1
R 2
(-5875 3475);
FORCEPROP 3 LASTPIN (-5825 3475) SIG_NAME P3E_CPU0_PE3_OCP_RXP<14>
J 0
(-5815 3485);
DISPLAY 0.659574 (-5815 3485);
PAINT MONO (-5815 3485);
DISPLAY INVISIBLE (-5815 3485);
FORCEPROP 1 LASTPIN (-5825 3475) BN 14
J 2
(-5813 3483);
DISPLAY 0.617021 (-5813 3483);
PAINT PINK (-5813 3483);
FORCEPROP 2 LAST CDS_LIB mstr_standard
J 0
(-5875 3475);
PAINT MONO (-5875 3475);
DISPLAY INVISIBLE (-5875 3475);
FORCEPROP 1 LAST BODY_TYPE PLUMBING
J 2
(-5875 3525);
DISPLAY 1.446809 (-5875 3525);
PAINT GREEN (-5875 3525);
DISPLAY INVISIBLE (-5875 3525);
FORCEPROP 1 LAST HDL_TAP TRUE
J 2
(-6200 3350);
DISPLAY 1.446809 (-6200 3350);
PAINT GREEN (-6200 3350);
DISPLAY INVISIBLE (-6200 3350);
FORCEPROP 1 LAST PATH I34
J 2
(-5873 3475);
DISPLAY 0.872340 (-5873 3475);
PAINT GREEN (-5873 3475);
DISPLAY INVISIBLE (-5873 3475);
FORCEADD TAP..1
R 2
(-5875 3525);
FORCEPROP 3 LASTPIN (-5825 3525) SIG_NAME P3E_CPU0_PE3_OCP_RXP<15>
J 0
(-5815 3535);
DISPLAY 0.659574 (-5815 3535);
PAINT MONO (-5815 3535);
DISPLAY INVISIBLE (-5815 3535);
FORCEPROP 1 LASTPIN (-5825 3525) BN 15
J 2
(-5813 3533);
DISPLAY 0.617021 (-5813 3533);
PAINT PINK (-5813 3533);
FORCEPROP 2 LAST CDS_LIB mstr_standard
J 0
(-5875 3525);
PAINT MONO (-5875 3525);
DISPLAY INVISIBLE (-5875 3525);
FORCEPROP 1 LAST BODY_TYPE PLUMBING
J 2
(-5875 3575);
DISPLAY 1.446809 (-5875 3575);
PAINT GREEN (-5875 3575);
DISPLAY INVISIBLE (-5875 3575);
FORCEPROP 1 LAST HDL_TAP TRUE
J 2
(-6200 3400);
DISPLAY 1.446809 (-6200 3400);
PAINT GREEN (-6200 3400);
DISPLAY INVISIBLE (-6200 3400);
FORCEPROP 1 LAST PATH I35
J 2
(-5873 3525);
DISPLAY 0.872340 (-5873 3525);
PAINT GREEN (-5873 3525);
DISPLAY INVISIBLE (-5873 3525);
FORCEADD TAP..1
(-3000 1875);
FORCEPROP 3 LASTPIN (-3050 1875) SIG_NAME P3E_CPU0_PE3_OCP_TXP<0>
J 0
(-3040 1885);
DISPLAY 0.659574 (-3040 1885);
PAINT MONO (-3040 1885);
DISPLAY INVISIBLE (-3040 1885);
FORCEPROP 1 LASTPIN (-3050 1875) BN 0
J 0
(-3062 1883);
DISPLAY 0.617021 (-3062 1883);
PAINT PINK (-3062 1883);
FORCEPROP 2 LAST CDS_LIB mstr_standard
J 2
(-3000 1875);
PAINT MONO (-3000 1875);
DISPLAY INVISIBLE (-3000 1875);
FORCEPROP 1 LAST BODY_TYPE PLUMBING
J 0
(-3000 1925);
DISPLAY 1.446809 (-3000 1925);
PAINT GREEN (-3000 1925);
DISPLAY INVISIBLE (-3000 1925);
FORCEPROP 1 LAST HDL_TAP TRUE
J 0
(-2675 1750);
DISPLAY 1.446809 (-2675 1750);
PAINT GREEN (-2675 1750);
DISPLAY INVISIBLE (-2675 1750);
FORCEPROP 1 LAST PATH I36
J 0
(-3002 1875);
DISPLAY 0.872340 (-3002 1875);
PAINT GREEN (-3002 1875);
DISPLAY INVISIBLE (-3002 1875);
FORCEADD TAP..1
(-3000 1975);
FORCEPROP 3 LASTPIN (-3050 1975) SIG_NAME P3E_CPU0_PE3_OCP_TXP<2>
J 0
(-3040 1985);
DISPLAY 0.659574 (-3040 1985);
PAINT MONO (-3040 1985);
DISPLAY INVISIBLE (-3040 1985);
FORCEPROP 1 LASTPIN (-3050 1975) BN 2
J 0
(-3062 1983);
DISPLAY 0.617021 (-3062 1983);
PAINT PINK (-3062 1983);
FORCEPROP 2 LAST CDS_LIB mstr_standard
J 2
(-3000 1975);
PAINT MONO (-3000 1975);
DISPLAY INVISIBLE (-3000 1975);
FORCEPROP 1 LAST BODY_TYPE PLUMBING
J 0
(-3000 2025);
DISPLAY 1.446809 (-3000 2025);
PAINT GREEN (-3000 2025);
DISPLAY INVISIBLE (-3000 2025);
FORCEPROP 1 LAST HDL_TAP TRUE
J 0
(-2675 1850);
DISPLAY 1.446809 (-2675 1850);
PAINT GREEN (-2675 1850);
DISPLAY INVISIBLE (-2675 1850);
FORCEPROP 1 LAST PATH I37
J 0
(-3002 1975);
DISPLAY 0.872340 (-3002 1975);
PAINT GREEN (-3002 1975);
DISPLAY INVISIBLE (-3002 1975);
FORCEADD TAP..1
(-3000 1925);
FORCEPROP 3 LASTPIN (-3050 1925) SIG_NAME P3E_CPU0_PE3_OCP_TXP<1>
J 0
(-3040 1935);
DISPLAY 0.659574 (-3040 1935);
PAINT MONO (-3040 1935);
DISPLAY INVISIBLE (-3040 1935);
FORCEPROP 1 LASTPIN (-3050 1925) BN 1
J 0
(-3062 1933);
DISPLAY 0.617021 (-3062 1933);
PAINT PINK (-3062 1933);
FORCEPROP 2 LAST CDS_LIB mstr_standard
J 2
(-3000 1925);
PAINT MONO (-3000 1925);
DISPLAY INVISIBLE (-3000 1925);
FORCEPROP 1 LAST BODY_TYPE PLUMBING
J 0
(-3000 1975);
DISPLAY 1.446809 (-3000 1975);
PAINT GREEN (-3000 1975);
DISPLAY INVISIBLE (-3000 1975);
FORCEPROP 1 LAST HDL_TAP TRUE
J 0
(-2675 1800);
DISPLAY 1.446809 (-2675 1800);
PAINT GREEN (-2675 1800);
DISPLAY INVISIBLE (-2675 1800);
FORCEPROP 1 LAST PATH I38
J 0
(-3002 1925);
DISPLAY 0.872340 (-3002 1925);
PAINT GREEN (-3002 1925);
DISPLAY INVISIBLE (-3002 1925);
FORCEADD TAP..1
(-2850 1625);
FORCEPROP 3 LASTPIN (-2900 1625) SIG_NAME P3E_CPU0_PE3_OCP_TXN<0>
J 0
(-2890 1635);
DISPLAY 0.659574 (-2890 1635);
PAINT MONO (-2890 1635);
DISPLAY INVISIBLE (-2890 1635);
FORCEPROP 1 LASTPIN (-2900 1625) BN 0
J 0
(-2912 1633);
DISPLAY 0.617021 (-2912 1633);
PAINT PINK (-2912 1633);
FORCEPROP 2 LAST CDS_LIB mstr_standard
J 2
(-2850 1625);
PAINT MONO (-2850 1625);
DISPLAY INVISIBLE (-2850 1625);
FORCEPROP 1 LAST BODY_TYPE PLUMBING
J 0
(-2850 1675);
DISPLAY 1.446809 (-2850 1675);
PAINT GREEN (-2850 1675);
DISPLAY INVISIBLE (-2850 1675);
FORCEPROP 1 LAST HDL_TAP TRUE
J 0
(-2525 1500);
DISPLAY 1.446809 (-2525 1500);
PAINT GREEN (-2525 1500);
DISPLAY INVISIBLE (-2525 1500);
FORCEPROP 1 LAST PATH I39
J 0
(-2852 1625);
DISPLAY 0.872340 (-2852 1625);
PAINT GREEN (-2852 1625);
DISPLAY INVISIBLE (-2852 1625);
FORCEADD TAP..1
R 2
(-6025 1675);
FORCEPROP 3 LASTPIN (-5975 1675) SIG_NAME P3E_CPU0_PE3_OCP_RXN<1>
J 0
(-5965 1685);
DISPLAY 0.659574 (-5965 1685);
PAINT MONO (-5965 1685);
DISPLAY INVISIBLE (-5965 1685);
FORCEPROP 1 LASTPIN (-5975 1675) BN 1
J 2
(-5963 1683);
DISPLAY 0.617021 (-5963 1683);
PAINT PINK (-5963 1683);
FORCEPROP 2 LAST CDS_LIB mstr_standard
J 0
(-6025 1675);
PAINT MONO (-6025 1675);
DISPLAY INVISIBLE (-6025 1675);
FORCEPROP 1 LAST BODY_TYPE PLUMBING
J 2
(-6025 1725);
DISPLAY 1.446809 (-6025 1725);
PAINT GREEN (-6025 1725);
DISPLAY INVISIBLE (-6025 1725);
FORCEPROP 1 LAST HDL_TAP TRUE
J 2
(-6350 1550);
DISPLAY 1.446809 (-6350 1550);
PAINT GREEN (-6350 1550);
DISPLAY INVISIBLE (-6350 1550);
FORCEPROP 1 LAST PATH I4
J 2
(-6023 1675);
DISPLAY 0.872340 (-6023 1675);
PAINT GREEN (-6023 1675);
DISPLAY INVISIBLE (-6023 1675);
FORCEADD TAP..1
(-2850 1675);
FORCEPROP 3 LASTPIN (-2900 1675) SIG_NAME P3E_CPU0_PE3_OCP_TXN<1>
J 0
(-2890 1685);
DISPLAY 0.659574 (-2890 1685);
PAINT MONO (-2890 1685);
DISPLAY INVISIBLE (-2890 1685);
FORCEPROP 1 LASTPIN (-2900 1675) BN 1
J 0
(-2912 1683);
DISPLAY 0.617021 (-2912 1683);
PAINT PINK (-2912 1683);
FORCEPROP 2 LAST CDS_LIB mstr_standard
J 2
(-2850 1675);
PAINT MONO (-2850 1675);
DISPLAY INVISIBLE (-2850 1675);
FORCEPROP 1 LAST BODY_TYPE PLUMBING
J 0
(-2850 1725);
DISPLAY 1.446809 (-2850 1725);
PAINT GREEN (-2850 1725);
DISPLAY INVISIBLE (-2850 1725);
FORCEPROP 1 LAST HDL_TAP TRUE
J 0
(-2525 1550);
DISPLAY 1.446809 (-2525 1550);
PAINT GREEN (-2525 1550);
DISPLAY INVISIBLE (-2525 1550);
FORCEPROP 1 LAST PATH I40
J 0
(-2852 1675);
DISPLAY 0.872340 (-2852 1675);
PAINT GREEN (-2852 1675);
DISPLAY INVISIBLE (-2852 1675);
FORCEADD TAP..1
(-2850 1725);
FORCEPROP 3 LASTPIN (-2900 1725) SIG_NAME P3E_CPU0_PE3_OCP_TXN<2>
J 0
(-2890 1735);
DISPLAY 0.659574 (-2890 1735);
PAINT MONO (-2890 1735);
DISPLAY INVISIBLE (-2890 1735);
FORCEPROP 1 LASTPIN (-2900 1725) BN 2
J 0
(-2912 1733);
DISPLAY 0.617021 (-2912 1733);
PAINT PINK (-2912 1733);
FORCEPROP 2 LAST CDS_LIB mstr_standard
J 2
(-2850 1725);
PAINT MONO (-2850 1725);
DISPLAY INVISIBLE (-2850 1725);
FORCEPROP 1 LAST BODY_TYPE PLUMBING
J 0
(-2850 1775);
DISPLAY 1.446809 (-2850 1775);
PAINT GREEN (-2850 1775);
DISPLAY INVISIBLE (-2850 1775);
FORCEPROP 1 LAST HDL_TAP TRUE
J 0
(-2525 1600);
DISPLAY 1.446809 (-2525 1600);
PAINT GREEN (-2525 1600);
DISPLAY INVISIBLE (-2525 1600);
FORCEPROP 1 LAST PATH I41
J 0
(-2852 1725);
DISPLAY 0.872340 (-2852 1725);
PAINT GREEN (-2852 1725);
DISPLAY INVISIBLE (-2852 1725);
FORCEADD TAP..1
(-2850 1775);
FORCEPROP 3 LASTPIN (-2900 1775) SIG_NAME P3E_CPU0_PE3_OCP_TXN<3>
J 0
(-2890 1785);
DISPLAY 0.659574 (-2890 1785);
PAINT MONO (-2890 1785);
DISPLAY INVISIBLE (-2890 1785);
FORCEPROP 1 LASTPIN (-2900 1775) BN 3
J 0
(-2912 1783);
DISPLAY 0.617021 (-2912 1783);
PAINT PINK (-2912 1783);
FORCEPROP 2 LAST CDS_LIB mstr_standard
J 2
(-2850 1775);
PAINT MONO (-2850 1775);
DISPLAY INVISIBLE (-2850 1775);
FORCEPROP 1 LAST BODY_TYPE PLUMBING
J 0
(-2850 1825);
DISPLAY 1.446809 (-2850 1825);
PAINT GREEN (-2850 1825);
DISPLAY INVISIBLE (-2850 1825);
FORCEPROP 1 LAST HDL_TAP TRUE
J 0
(-2525 1650);
DISPLAY 1.446809 (-2525 1650);
PAINT GREEN (-2525 1650);
DISPLAY INVISIBLE (-2525 1650);
FORCEPROP 1 LAST PATH I42
J 0
(-2852 1775);
DISPLAY 0.872340 (-2852 1775);
PAINT GREEN (-2852 1775);
DISPLAY INVISIBLE (-2852 1775);
FORCEADD TAP..1
(-3000 2475);
FORCEPROP 3 LASTPIN (-3050 2475) SIG_NAME P3E_CPU0_PE3_OCP_TXP<6>
J 0
(-3040 2485);
DISPLAY 0.659574 (-3040 2485);
PAINT MONO (-3040 2485);
DISPLAY INVISIBLE (-3040 2485);
FORCEPROP 1 LASTPIN (-3050 2475) BN 6
J 0
(-3062 2483);
DISPLAY 0.617021 (-3062 2483);
PAINT PINK (-3062 2483);
FORCEPROP 2 LAST CDS_LIB mstr_standard
J 2
(-3000 2475);
PAINT MONO (-3000 2475);
DISPLAY INVISIBLE (-3000 2475);
FORCEPROP 1 LAST BODY_TYPE PLUMBING
J 0
(-3000 2525);
DISPLAY 1.446809 (-3000 2525);
PAINT GREEN (-3000 2525);
DISPLAY INVISIBLE (-3000 2525);
FORCEPROP 1 LAST HDL_TAP TRUE
J 0
(-2675 2350);
DISPLAY 1.446809 (-2675 2350);
PAINT GREEN (-2675 2350);
DISPLAY INVISIBLE (-2675 2350);
FORCEPROP 1 LAST PATH I43
J 0
(-3002 2475);
DISPLAY 0.872340 (-3002 2475);
PAINT GREEN (-3002 2475);
DISPLAY INVISIBLE (-3002 2475);
FORCEADD TAP..1
(-3000 2525);
FORCEPROP 3 LASTPIN (-3050 2525) SIG_NAME P3E_CPU0_PE3_OCP_TXP<7>
J 0
(-3040 2535);
DISPLAY 0.659574 (-3040 2535);
PAINT MONO (-3040 2535);
DISPLAY INVISIBLE (-3040 2535);
FORCEPROP 1 LASTPIN (-3050 2525) BN 7
J 0
(-3062 2533);
DISPLAY 0.617021 (-3062 2533);
PAINT PINK (-3062 2533);
FORCEPROP 2 LAST CDS_LIB mstr_standard
J 2
(-3000 2525);
PAINT MONO (-3000 2525);
DISPLAY INVISIBLE (-3000 2525);
FORCEPROP 1 LAST BODY_TYPE PLUMBING
J 0
(-3000 2575);
DISPLAY 1.446809 (-3000 2575);
PAINT GREEN (-3000 2575);
DISPLAY INVISIBLE (-3000 2575);
FORCEPROP 1 LAST HDL_TAP TRUE
J 0
(-2675 2400);
DISPLAY 1.446809 (-2675 2400);
PAINT GREEN (-2675 2400);
DISPLAY INVISIBLE (-2675 2400);
FORCEPROP 1 LAST PATH I44
J 0
(-3002 2525);
DISPLAY 0.872340 (-3002 2525);
PAINT GREEN (-3002 2525);
DISPLAY INVISIBLE (-3002 2525);
FORCEADD TAP..1
(-3000 2425);
FORCEPROP 3 LASTPIN (-3050 2425) SIG_NAME P3E_CPU0_PE3_OCP_TXP<5>
J 0
(-3040 2435);
DISPLAY 0.659574 (-3040 2435);
PAINT MONO (-3040 2435);
DISPLAY INVISIBLE (-3040 2435);
FORCEPROP 1 LASTPIN (-3050 2425) BN 5
J 0
(-3062 2433);
DISPLAY 0.617021 (-3062 2433);
PAINT PINK (-3062 2433);
FORCEPROP 2 LAST CDS_LIB mstr_standard
J 2
(-3000 2425);
PAINT MONO (-3000 2425);
DISPLAY INVISIBLE (-3000 2425);
FORCEPROP 1 LAST BODY_TYPE PLUMBING
J 0
(-3000 2475);
DISPLAY 1.446809 (-3000 2475);
PAINT GREEN (-3000 2475);
DISPLAY INVISIBLE (-3000 2475);
FORCEPROP 1 LAST HDL_TAP TRUE
J 0
(-2675 2300);
DISPLAY 1.446809 (-2675 2300);
PAINT GREEN (-2675 2300);
DISPLAY INVISIBLE (-2675 2300);
FORCEPROP 1 LAST PATH I45
J 0
(-3002 2425);
DISPLAY 0.872340 (-3002 2425);
PAINT GREEN (-3002 2425);
DISPLAY INVISIBLE (-3002 2425);
FORCEADD TAP..1
(-3000 2375);
FORCEPROP 3 LASTPIN (-3050 2375) SIG_NAME P3E_CPU0_PE3_OCP_TXP<4>
J 0
(-3040 2385);
DISPLAY 0.659574 (-3040 2385);
PAINT MONO (-3040 2385);
DISPLAY INVISIBLE (-3040 2385);
FORCEPROP 1 LASTPIN (-3050 2375) BN 4
J 0
(-3062 2383);
DISPLAY 0.617021 (-3062 2383);
PAINT PINK (-3062 2383);
FORCEPROP 2 LAST CDS_LIB mstr_standard
J 2
(-3000 2375);
PAINT MONO (-3000 2375);
DISPLAY INVISIBLE (-3000 2375);
FORCEPROP 1 LAST BODY_TYPE PLUMBING
J 0
(-3000 2425);
DISPLAY 1.446809 (-3000 2425);
PAINT GREEN (-3000 2425);
DISPLAY INVISIBLE (-3000 2425);
FORCEPROP 1 LAST HDL_TAP TRUE
J 0
(-2675 2250);
DISPLAY 1.446809 (-2675 2250);
PAINT GREEN (-2675 2250);
DISPLAY INVISIBLE (-2675 2250);
FORCEPROP 1 LAST PATH I46
J 0
(-3002 2375);
DISPLAY 0.872340 (-3002 2375);
PAINT GREEN (-3002 2375);
DISPLAY INVISIBLE (-3002 2375);
FORCEADD TAP..1
(-3000 2025);
FORCEPROP 3 LASTPIN (-3050 2025) SIG_NAME P3E_CPU0_PE3_OCP_TXP<3>
J 0
(-3040 2035);
DISPLAY 0.659574 (-3040 2035);
PAINT MONO (-3040 2035);
DISPLAY INVISIBLE (-3040 2035);
FORCEPROP 1 LASTPIN (-3050 2025) BN 3
J 0
(-3062 2033);
DISPLAY 0.617021 (-3062 2033);
PAINT PINK (-3062 2033);
FORCEPROP 2 LAST CDS_LIB mstr_standard
J 2
(-3000 2025);
PAINT MONO (-3000 2025);
DISPLAY INVISIBLE (-3000 2025);
FORCEPROP 1 LAST BODY_TYPE PLUMBING
J 0
(-3000 2075);
DISPLAY 1.446809 (-3000 2075);
PAINT GREEN (-3000 2075);
DISPLAY INVISIBLE (-3000 2075);
FORCEPROP 1 LAST HDL_TAP TRUE
J 0
(-2675 1900);
DISPLAY 1.446809 (-2675 1900);
PAINT GREEN (-2675 1900);
DISPLAY INVISIBLE (-2675 1900);
FORCEPROP 1 LAST PATH I47
J 0
(-3002 2025);
DISPLAY 0.872340 (-3002 2025);
PAINT GREEN (-3002 2025);
DISPLAY INVISIBLE (-3002 2025);
FORCEADD TAP..1
(-2850 2125);
FORCEPROP 3 LASTPIN (-2900 2125) SIG_NAME P3E_CPU0_PE3_OCP_TXN<4>
J 0
(-2890 2135);
DISPLAY 0.659574 (-2890 2135);
PAINT MONO (-2890 2135);
DISPLAY INVISIBLE (-2890 2135);
FORCEPROP 1 LASTPIN (-2900 2125) BN 4
J 0
(-2912 2133);
DISPLAY 0.617021 (-2912 2133);
PAINT PINK (-2912 2133);
FORCEPROP 2 LAST CDS_LIB mstr_standard
J 2
(-2850 2125);
PAINT MONO (-2850 2125);
DISPLAY INVISIBLE (-2850 2125);
FORCEPROP 1 LAST BODY_TYPE PLUMBING
J 0
(-2850 2175);
DISPLAY 1.446809 (-2850 2175);
PAINT GREEN (-2850 2175);
DISPLAY INVISIBLE (-2850 2175);
FORCEPROP 1 LAST HDL_TAP TRUE
J 0
(-2525 2000);
DISPLAY 1.446809 (-2525 2000);
PAINT GREEN (-2525 2000);
DISPLAY INVISIBLE (-2525 2000);
FORCEPROP 1 LAST PATH I48
J 0
(-2852 2125);
DISPLAY 0.872340 (-2852 2125);
PAINT GREEN (-2852 2125);
DISPLAY INVISIBLE (-2852 2125);
FORCEADD TAP..1
(-2850 2175);
FORCEPROP 3 LASTPIN (-2900 2175) SIG_NAME P3E_CPU0_PE3_OCP_TXN<5>
J 0
(-2890 2185);
DISPLAY 0.659574 (-2890 2185);
PAINT MONO (-2890 2185);
DISPLAY INVISIBLE (-2890 2185);
FORCEPROP 1 LASTPIN (-2900 2175) BN 5
J 0
(-2912 2183);
DISPLAY 0.617021 (-2912 2183);
PAINT PINK (-2912 2183);
FORCEPROP 2 LAST CDS_LIB mstr_standard
J 2
(-2850 2175);
PAINT MONO (-2850 2175);
DISPLAY INVISIBLE (-2850 2175);
FORCEPROP 1 LAST BODY_TYPE PLUMBING
J 0
(-2850 2225);
DISPLAY 1.446809 (-2850 2225);
PAINT GREEN (-2850 2225);
DISPLAY INVISIBLE (-2850 2225);
FORCEPROP 1 LAST HDL_TAP TRUE
J 0
(-2525 2050);
DISPLAY 1.446809 (-2525 2050);
PAINT GREEN (-2525 2050);
DISPLAY INVISIBLE (-2525 2050);
FORCEPROP 1 LAST PATH I49
J 0
(-2852 2175);
DISPLAY 0.872340 (-2852 2175);
PAINT GREEN (-2852 2175);
DISPLAY INVISIBLE (-2852 2175);
FORCEADD TAP..1
R 2
(-6025 1725);
FORCEPROP 3 LASTPIN (-5975 1725) SIG_NAME P3E_CPU0_PE3_OCP_RXN<2>
J 0
(-5965 1735);
DISPLAY 0.659574 (-5965 1735);
PAINT MONO (-5965 1735);
DISPLAY INVISIBLE (-5965 1735);
FORCEPROP 1 LASTPIN (-5975 1725) BN 2
J 2
(-5963 1733);
DISPLAY 0.617021 (-5963 1733);
PAINT PINK (-5963 1733);
FORCEPROP 2 LAST CDS_LIB mstr_standard
J 0
(-6025 1725);
PAINT MONO (-6025 1725);
DISPLAY INVISIBLE (-6025 1725);
FORCEPROP 1 LAST BODY_TYPE PLUMBING
J 2
(-6025 1775);
DISPLAY 1.446809 (-6025 1775);
PAINT GREEN (-6025 1775);
DISPLAY INVISIBLE (-6025 1775);
FORCEPROP 1 LAST HDL_TAP TRUE
J 2
(-6350 1600);
DISPLAY 1.446809 (-6350 1600);
PAINT GREEN (-6350 1600);
DISPLAY INVISIBLE (-6350 1600);
FORCEPROP 1 LAST PATH I5
J 2
(-6023 1725);
DISPLAY 0.872340 (-6023 1725);
PAINT GREEN (-6023 1725);
DISPLAY INVISIBLE (-6023 1725);
FORCEADD TAP..1
(-2850 2225);
FORCEPROP 3 LASTPIN (-2900 2225) SIG_NAME P3E_CPU0_PE3_OCP_TXN<6>
J 0
(-2890 2235);
DISPLAY 0.659574 (-2890 2235);
PAINT MONO (-2890 2235);
DISPLAY INVISIBLE (-2890 2235);
FORCEPROP 1 LASTPIN (-2900 2225) BN 6
J 0
(-2912 2233);
DISPLAY 0.617021 (-2912 2233);
PAINT PINK (-2912 2233);
FORCEPROP 2 LAST CDS_LIB mstr_standard
J 2
(-2850 2225);
PAINT MONO (-2850 2225);
DISPLAY INVISIBLE (-2850 2225);
FORCEPROP 1 LAST BODY_TYPE PLUMBING
J 0
(-2850 2275);
DISPLAY 1.446809 (-2850 2275);
PAINT GREEN (-2850 2275);
DISPLAY INVISIBLE (-2850 2275);
FORCEPROP 1 LAST HDL_TAP TRUE
J 0
(-2525 2100);
DISPLAY 1.446809 (-2525 2100);
PAINT GREEN (-2525 2100);
DISPLAY INVISIBLE (-2525 2100);
FORCEPROP 1 LAST PATH I50
J 0
(-2852 2225);
DISPLAY 0.872340 (-2852 2225);
PAINT GREEN (-2852 2225);
DISPLAY INVISIBLE (-2852 2225);
FORCEADD TAP..1
(-2850 2275);
FORCEPROP 3 LASTPIN (-2900 2275) SIG_NAME P3E_CPU0_PE3_OCP_TXN<7>
J 0
(-2890 2285);
DISPLAY 0.659574 (-2890 2285);
PAINT MONO (-2890 2285);
DISPLAY INVISIBLE (-2890 2285);
FORCEPROP 1 LASTPIN (-2900 2275) BN 7
J 0
(-2912 2283);
DISPLAY 0.617021 (-2912 2283);
PAINT PINK (-2912 2283);
FORCEPROP 2 LAST CDS_LIB mstr_standard
J 2
(-2850 2275);
PAINT MONO (-2850 2275);
DISPLAY INVISIBLE (-2850 2275);
FORCEPROP 1 LAST BODY_TYPE PLUMBING
J 0
(-2850 2325);
DISPLAY 1.446809 (-2850 2325);
PAINT GREEN (-2850 2325);
DISPLAY INVISIBLE (-2850 2325);
FORCEPROP 1 LAST HDL_TAP TRUE
J 0
(-2525 2150);
DISPLAY 1.446809 (-2525 2150);
PAINT GREEN (-2525 2150);
DISPLAY INVISIBLE (-2525 2150);
FORCEPROP 1 LAST PATH I51
J 0
(-2852 2275);
DISPLAY 0.872340 (-2852 2275);
PAINT GREEN (-2852 2275);
DISPLAY INVISIBLE (-2852 2275);
FORCEADD TAP..1
(-3000 2975);
FORCEPROP 3 LASTPIN (-3050 2975) SIG_NAME P3E_CPU0_PE3_OCP_TXP<10>
J 0
(-3040 2985);
DISPLAY 0.659574 (-3040 2985);
PAINT MONO (-3040 2985);
DISPLAY INVISIBLE (-3040 2985);
FORCEPROP 1 LASTPIN (-3050 2975) BN 10
J 0
(-3062 2983);
DISPLAY 0.617021 (-3062 2983);
PAINT PINK (-3062 2983);
FORCEPROP 2 LAST CDS_LIB mstr_standard
J 2
(-3000 2975);
PAINT MONO (-3000 2975);
DISPLAY INVISIBLE (-3000 2975);
FORCEPROP 1 LAST BODY_TYPE PLUMBING
J 0
(-3000 3025);
DISPLAY 1.446809 (-3000 3025);
PAINT GREEN (-3000 3025);
DISPLAY INVISIBLE (-3000 3025);
FORCEPROP 1 LAST HDL_TAP TRUE
J 0
(-2675 2850);
DISPLAY 1.446809 (-2675 2850);
PAINT GREEN (-2675 2850);
DISPLAY INVISIBLE (-2675 2850);
FORCEPROP 1 LAST PATH I52
J 0
(-3002 2975);
DISPLAY 0.872340 (-3002 2975);
PAINT GREEN (-3002 2975);
DISPLAY INVISIBLE (-3002 2975);
FORCEADD TAP..1
(-3000 3025);
FORCEPROP 3 LASTPIN (-3050 3025) SIG_NAME P3E_CPU0_PE3_OCP_TXP<11>
J 0
(-3040 3035);
DISPLAY 0.659574 (-3040 3035);
PAINT MONO (-3040 3035);
DISPLAY INVISIBLE (-3040 3035);
FORCEPROP 1 LASTPIN (-3050 3025) BN 11
J 0
(-3062 3033);
DISPLAY 0.617021 (-3062 3033);
PAINT PINK (-3062 3033);
FORCEPROP 2 LAST CDS_LIB mstr_standard
J 2
(-3000 3025);
PAINT MONO (-3000 3025);
DISPLAY INVISIBLE (-3000 3025);
FORCEPROP 1 LAST BODY_TYPE PLUMBING
J 0
(-3000 3075);
DISPLAY 1.446809 (-3000 3075);
PAINT GREEN (-3000 3075);
DISPLAY INVISIBLE (-3000 3075);
FORCEPROP 1 LAST HDL_TAP TRUE
J 0
(-2675 2900);
DISPLAY 1.446809 (-2675 2900);
PAINT GREEN (-2675 2900);
DISPLAY INVISIBLE (-2675 2900);
FORCEPROP 1 LAST PATH I53
J 0
(-3002 3025);
DISPLAY 0.872340 (-3002 3025);
PAINT GREEN (-3002 3025);
DISPLAY INVISIBLE (-3002 3025);
FORCEADD TAP..1
(-3000 2925);
FORCEPROP 3 LASTPIN (-3050 2925) SIG_NAME P3E_CPU0_PE3_OCP_TXP<9>
J 0
(-3040 2935);
DISPLAY 0.659574 (-3040 2935);
PAINT MONO (-3040 2935);
DISPLAY INVISIBLE (-3040 2935);
FORCEPROP 1 LASTPIN (-3050 2925) BN 9
J 0
(-3062 2933);
DISPLAY 0.617021 (-3062 2933);
PAINT PINK (-3062 2933);
FORCEPROP 2 LAST CDS_LIB mstr_standard
J 2
(-3000 2925);
PAINT MONO (-3000 2925);
DISPLAY INVISIBLE (-3000 2925);
FORCEPROP 1 LAST BODY_TYPE PLUMBING
J 0
(-3000 2975);
DISPLAY 1.446809 (-3000 2975);
PAINT GREEN (-3000 2975);
DISPLAY INVISIBLE (-3000 2975);
FORCEPROP 1 LAST HDL_TAP TRUE
J 0
(-2675 2800);
DISPLAY 1.446809 (-2675 2800);
PAINT GREEN (-2675 2800);
DISPLAY INVISIBLE (-2675 2800);
FORCEPROP 1 LAST PATH I54
J 0
(-3002 2925);
DISPLAY 0.872340 (-3002 2925);
PAINT GREEN (-3002 2925);
DISPLAY INVISIBLE (-3002 2925);
FORCEADD TAP..1
(-3000 2875);
FORCEPROP 3 LASTPIN (-3050 2875) SIG_NAME P3E_CPU0_PE3_OCP_TXP<8>
J 0
(-3040 2885);
DISPLAY 0.659574 (-3040 2885);
PAINT MONO (-3040 2885);
DISPLAY INVISIBLE (-3040 2885);
FORCEPROP 1 LASTPIN (-3050 2875) BN 8
J 0
(-3062 2883);
DISPLAY 0.617021 (-3062 2883);
PAINT PINK (-3062 2883);
FORCEPROP 2 LAST CDS_LIB mstr_standard
J 2
(-3000 2875);
PAINT MONO (-3000 2875);
DISPLAY INVISIBLE (-3000 2875);
FORCEPROP 1 LAST BODY_TYPE PLUMBING
J 0
(-3000 2925);
DISPLAY 1.446809 (-3000 2925);
PAINT GREEN (-3000 2925);
DISPLAY INVISIBLE (-3000 2925);
FORCEPROP 1 LAST HDL_TAP TRUE
J 0
(-2675 2750);
DISPLAY 1.446809 (-2675 2750);
PAINT GREEN (-2675 2750);
DISPLAY INVISIBLE (-2675 2750);
FORCEPROP 1 LAST PATH I55
J 0
(-3002 2875);
DISPLAY 0.872340 (-3002 2875);
PAINT GREEN (-3002 2875);
DISPLAY INVISIBLE (-3002 2875);
FORCEADD TAP..1
(-2850 2625);
FORCEPROP 3 LASTPIN (-2900 2625) SIG_NAME P3E_CPU0_PE3_OCP_TXN<8>
J 0
(-2890 2635);
DISPLAY 0.659574 (-2890 2635);
PAINT MONO (-2890 2635);
DISPLAY INVISIBLE (-2890 2635);
FORCEPROP 1 LASTPIN (-2900 2625) BN 8
J 0
(-2912 2633);
DISPLAY 0.617021 (-2912 2633);
PAINT PINK (-2912 2633);
FORCEPROP 2 LAST CDS_LIB mstr_standard
J 2
(-2850 2625);
PAINT MONO (-2850 2625);
DISPLAY INVISIBLE (-2850 2625);
FORCEPROP 1 LAST BODY_TYPE PLUMBING
J 0
(-2850 2675);
DISPLAY 1.446809 (-2850 2675);
PAINT GREEN (-2850 2675);
DISPLAY INVISIBLE (-2850 2675);
FORCEPROP 1 LAST HDL_TAP TRUE
J 0
(-2525 2500);
DISPLAY 1.446809 (-2525 2500);
PAINT GREEN (-2525 2500);
DISPLAY INVISIBLE (-2525 2500);
FORCEPROP 1 LAST PATH I56
J 0
(-2852 2625);
DISPLAY 0.872340 (-2852 2625);
PAINT GREEN (-2852 2625);
DISPLAY INVISIBLE (-2852 2625);
FORCEADD TAP..1
(-2850 2725);
FORCEPROP 3 LASTPIN (-2900 2725) SIG_NAME P3E_CPU0_PE3_OCP_TXN<10>
J 0
(-2890 2735);
DISPLAY 0.659574 (-2890 2735);
PAINT MONO (-2890 2735);
DISPLAY INVISIBLE (-2890 2735);
FORCEPROP 1 LASTPIN (-2900 2725) BN 10
J 0
(-2912 2733);
DISPLAY 0.617021 (-2912 2733);
PAINT PINK (-2912 2733);
FORCEPROP 2 LAST CDS_LIB mstr_standard
J 2
(-2850 2725);
PAINT MONO (-2850 2725);
DISPLAY INVISIBLE (-2850 2725);
FORCEPROP 1 LAST BODY_TYPE PLUMBING
J 0
(-2850 2775);
DISPLAY 1.446809 (-2850 2775);
PAINT GREEN (-2850 2775);
DISPLAY INVISIBLE (-2850 2775);
FORCEPROP 1 LAST HDL_TAP TRUE
J 0
(-2525 2600);
DISPLAY 1.446809 (-2525 2600);
PAINT GREEN (-2525 2600);
DISPLAY INVISIBLE (-2525 2600);
FORCEPROP 1 LAST PATH I57
J 0
(-2852 2725);
DISPLAY 0.872340 (-2852 2725);
PAINT GREEN (-2852 2725);
DISPLAY INVISIBLE (-2852 2725);
FORCEADD TAP..1
(-2850 2675);
FORCEPROP 3 LASTPIN (-2900 2675) SIG_NAME P3E_CPU0_PE3_OCP_TXN<9>
J 0
(-2890 2685);
DISPLAY 0.659574 (-2890 2685);
PAINT MONO (-2890 2685);
DISPLAY INVISIBLE (-2890 2685);
FORCEPROP 1 LASTPIN (-2900 2675) BN 9
J 0
(-2912 2683);
DISPLAY 0.617021 (-2912 2683);
PAINT PINK (-2912 2683);
FORCEPROP 2 LAST CDS_LIB mstr_standard
J 2
(-2850 2675);
PAINT MONO (-2850 2675);
DISPLAY INVISIBLE (-2850 2675);
FORCEPROP 1 LAST BODY_TYPE PLUMBING
J 0
(-2850 2725);
DISPLAY 1.446809 (-2850 2725);
PAINT GREEN (-2850 2725);
DISPLAY INVISIBLE (-2850 2725);
FORCEPROP 1 LAST HDL_TAP TRUE
J 0
(-2525 2550);
DISPLAY 1.446809 (-2525 2550);
PAINT GREEN (-2525 2550);
DISPLAY INVISIBLE (-2525 2550);
FORCEPROP 1 LAST PATH I58
J 0
(-2852 2675);
DISPLAY 0.872340 (-2852 2675);
PAINT GREEN (-2852 2675);
DISPLAY INVISIBLE (-2852 2675);
FORCEADD TAP..1
(-2850 2775);
FORCEPROP 3 LASTPIN (-2900 2775) SIG_NAME P3E_CPU0_PE3_OCP_TXN<11>
J 0
(-2890 2785);
DISPLAY 0.659574 (-2890 2785);
PAINT MONO (-2890 2785);
DISPLAY INVISIBLE (-2890 2785);
FORCEPROP 1 LASTPIN (-2900 2775) BN 11
J 0
(-2912 2783);
DISPLAY 0.617021 (-2912 2783);
PAINT PINK (-2912 2783);
FORCEPROP 2 LAST CDS_LIB mstr_standard
J 2
(-2850 2775);
PAINT MONO (-2850 2775);
DISPLAY INVISIBLE (-2850 2775);
FORCEPROP 1 LAST BODY_TYPE PLUMBING
J 0
(-2850 2825);
DISPLAY 1.446809 (-2850 2825);
PAINT GREEN (-2850 2825);
DISPLAY INVISIBLE (-2850 2825);
FORCEPROP 1 LAST HDL_TAP TRUE
J 0
(-2525 2650);
DISPLAY 1.446809 (-2525 2650);
PAINT GREEN (-2525 2650);
DISPLAY INVISIBLE (-2525 2650);
FORCEPROP 1 LAST PATH I59
J 0
(-2852 2775);
DISPLAY 0.872340 (-2852 2775);
PAINT GREEN (-2852 2775);
DISPLAY INVISIBLE (-2852 2775);
FORCEADD TAP..1
R 2
(-6025 1775);
FORCEPROP 3 LASTPIN (-5975 1775) SIG_NAME P3E_CPU0_PE3_OCP_RXN<3>
J 0
(-5965 1785);
DISPLAY 0.659574 (-5965 1785);
PAINT MONO (-5965 1785);
DISPLAY INVISIBLE (-5965 1785);
FORCEPROP 1 LASTPIN (-5975 1775) BN 3
J 2
(-5963 1783);
DISPLAY 0.617021 (-5963 1783);
PAINT PINK (-5963 1783);
FORCEPROP 2 LAST CDS_LIB mstr_standard
J 0
(-6025 1775);
PAINT MONO (-6025 1775);
DISPLAY INVISIBLE (-6025 1775);
FORCEPROP 1 LAST BODY_TYPE PLUMBING
J 2
(-6025 1825);
DISPLAY 1.446809 (-6025 1825);
PAINT GREEN (-6025 1825);
DISPLAY INVISIBLE (-6025 1825);
FORCEPROP 1 LAST HDL_TAP TRUE
J 2
(-6350 1650);
DISPLAY 1.446809 (-6350 1650);
PAINT GREEN (-6350 1650);
DISPLAY INVISIBLE (-6350 1650);
FORCEPROP 1 LAST PATH I6
J 2
(-6023 1775);
DISPLAY 0.872340 (-6023 1775);
PAINT GREEN (-6023 1775);
DISPLAY INVISIBLE (-6023 1775);
FORCEADD TAP..1
(-3000 3425);
FORCEPROP 3 LASTPIN (-3050 3425) SIG_NAME P3E_CPU0_PE3_OCP_TXP<13>
J 0
(-3040 3435);
DISPLAY 0.659574 (-3040 3435);
PAINT MONO (-3040 3435);
DISPLAY INVISIBLE (-3040 3435);
FORCEPROP 1 LASTPIN (-3050 3425) BN 13
J 0
(-3062 3433);
DISPLAY 0.617021 (-3062 3433);
PAINT PINK (-3062 3433);
FORCEPROP 2 LAST CDS_LIB mstr_standard
J 2
(-3000 3425);
PAINT MONO (-3000 3425);
DISPLAY INVISIBLE (-3000 3425);
FORCEPROP 1 LAST BODY_TYPE PLUMBING
J 0
(-3000 3475);
DISPLAY 1.446809 (-3000 3475);
PAINT GREEN (-3000 3475);
DISPLAY INVISIBLE (-3000 3475);
FORCEPROP 1 LAST HDL_TAP TRUE
J 0
(-2675 3300);
DISPLAY 1.446809 (-2675 3300);
PAINT GREEN (-2675 3300);
DISPLAY INVISIBLE (-2675 3300);
FORCEPROP 1 LAST PATH I60
J 0
(-3002 3425);
DISPLAY 0.872340 (-3002 3425);
PAINT GREEN (-3002 3425);
DISPLAY INVISIBLE (-3002 3425);
FORCEADD TAP..1
(-3000 3525);
FORCEPROP 3 LASTPIN (-3050 3525) SIG_NAME P3E_CPU0_PE3_OCP_TXP<15>
J 0
(-3040 3535);
DISPLAY 0.659574 (-3040 3535);
PAINT MONO (-3040 3535);
DISPLAY INVISIBLE (-3040 3535);
FORCEPROP 1 LASTPIN (-3050 3525) BN 15
J 0
(-3062 3533);
DISPLAY 0.617021 (-3062 3533);
PAINT PINK (-3062 3533);
FORCEPROP 2 LAST CDS_LIB mstr_standard
J 2
(-3000 3525);
PAINT MONO (-3000 3525);
DISPLAY INVISIBLE (-3000 3525);
FORCEPROP 1 LAST BODY_TYPE PLUMBING
J 0
(-3000 3575);
DISPLAY 1.446809 (-3000 3575);
PAINT GREEN (-3000 3575);
DISPLAY INVISIBLE (-3000 3575);
FORCEPROP 1 LAST HDL_TAP TRUE
J 0
(-2675 3400);
DISPLAY 1.446809 (-2675 3400);
PAINT GREEN (-2675 3400);
DISPLAY INVISIBLE (-2675 3400);
FORCEPROP 1 LAST PATH I61
J 0
(-3002 3525);
DISPLAY 0.872340 (-3002 3525);
PAINT GREEN (-3002 3525);
DISPLAY INVISIBLE (-3002 3525);
FORCEADD TAP..1
(-3000 3375);
FORCEPROP 3 LASTPIN (-3050 3375) SIG_NAME P3E_CPU0_PE3_OCP_TXP<12>
J 0
(-3040 3385);
DISPLAY 0.659574 (-3040 3385);
PAINT MONO (-3040 3385);
DISPLAY INVISIBLE (-3040 3385);
FORCEPROP 1 LASTPIN (-3050 3375) BN 12
J 0
(-3062 3383);
DISPLAY 0.617021 (-3062 3383);
PAINT PINK (-3062 3383);
FORCEPROP 2 LAST CDS_LIB mstr_standard
J 2
(-3000 3375);
PAINT MONO (-3000 3375);
DISPLAY INVISIBLE (-3000 3375);
FORCEPROP 1 LAST BODY_TYPE PLUMBING
J 0
(-3000 3425);
DISPLAY 1.446809 (-3000 3425);
PAINT GREEN (-3000 3425);
DISPLAY INVISIBLE (-3000 3425);
FORCEPROP 1 LAST HDL_TAP TRUE
J 0
(-2675 3250);
DISPLAY 1.446809 (-2675 3250);
PAINT GREEN (-2675 3250);
DISPLAY INVISIBLE (-2675 3250);
FORCEPROP 1 LAST PATH I62
J 0
(-3002 3375);
DISPLAY 0.872340 (-3002 3375);
PAINT GREEN (-3002 3375);
DISPLAY INVISIBLE (-3002 3375);
FORCEADD TAP..1
(-3000 3475);
FORCEPROP 3 LASTPIN (-3050 3475) SIG_NAME P3E_CPU0_PE3_OCP_TXP<14>
J 0
(-3040 3485);
DISPLAY 0.659574 (-3040 3485);
PAINT MONO (-3040 3485);
DISPLAY INVISIBLE (-3040 3485);
FORCEPROP 1 LASTPIN (-3050 3475) BN 14
J 0
(-3062 3483);
DISPLAY 0.617021 (-3062 3483);
PAINT PINK (-3062 3483);
FORCEPROP 2 LAST CDS_LIB mstr_standard
J 2
(-3000 3475);
PAINT MONO (-3000 3475);
DISPLAY INVISIBLE (-3000 3475);
FORCEPROP 1 LAST BODY_TYPE PLUMBING
J 0
(-3000 3525);
DISPLAY 1.446809 (-3000 3525);
PAINT GREEN (-3000 3525);
DISPLAY INVISIBLE (-3000 3525);
FORCEPROP 1 LAST HDL_TAP TRUE
J 0
(-2675 3350);
DISPLAY 1.446809 (-2675 3350);
PAINT GREEN (-2675 3350);
DISPLAY INVISIBLE (-2675 3350);
FORCEPROP 1 LAST PATH I63
J 0
(-3002 3475);
DISPLAY 0.872340 (-3002 3475);
PAINT GREEN (-3002 3475);
DISPLAY INVISIBLE (-3002 3475);
FORCEADD TAP..1
(-2850 3125);
FORCEPROP 3 LASTPIN (-2900 3125) SIG_NAME P3E_CPU0_PE3_OCP_TXN<12>
J 0
(-2890 3135);
DISPLAY 0.659574 (-2890 3135);
PAINT MONO (-2890 3135);
DISPLAY INVISIBLE (-2890 3135);
FORCEPROP 1 LASTPIN (-2900 3125) BN 12
J 0
(-2912 3133);
DISPLAY 0.617021 (-2912 3133);
PAINT PINK (-2912 3133);
FORCEPROP 2 LAST CDS_LIB mstr_standard
J 2
(-2850 3125);
PAINT MONO (-2850 3125);
DISPLAY INVISIBLE (-2850 3125);
FORCEPROP 1 LAST BODY_TYPE PLUMBING
J 0
(-2850 3175);
DISPLAY 1.446809 (-2850 3175);
PAINT GREEN (-2850 3175);
DISPLAY INVISIBLE (-2850 3175);
FORCEPROP 1 LAST HDL_TAP TRUE
J 0
(-2525 3000);
DISPLAY 1.446809 (-2525 3000);
PAINT GREEN (-2525 3000);
DISPLAY INVISIBLE (-2525 3000);
FORCEPROP 1 LAST PATH I64
J 0
(-2852 3125);
DISPLAY 0.872340 (-2852 3125);
PAINT GREEN (-2852 3125);
DISPLAY INVISIBLE (-2852 3125);
FORCEADD TAP..1
(-2850 3175);
FORCEPROP 3 LASTPIN (-2900 3175) SIG_NAME P3E_CPU0_PE3_OCP_TXN<13>
J 0
(-2890 3185);
DISPLAY 0.659574 (-2890 3185);
PAINT MONO (-2890 3185);
DISPLAY INVISIBLE (-2890 3185);
FORCEPROP 1 LASTPIN (-2900 3175) BN 13
J 0
(-2912 3183);
DISPLAY 0.617021 (-2912 3183);
PAINT PINK (-2912 3183);
FORCEPROP 2 LAST CDS_LIB mstr_standard
J 2
(-2850 3175);
PAINT MONO (-2850 3175);
DISPLAY INVISIBLE (-2850 3175);
FORCEPROP 1 LAST BODY_TYPE PLUMBING
J 0
(-2850 3225);
DISPLAY 1.446809 (-2850 3225);
PAINT GREEN (-2850 3225);
DISPLAY INVISIBLE (-2850 3225);
FORCEPROP 1 LAST HDL_TAP TRUE
J 0
(-2525 3050);
DISPLAY 1.446809 (-2525 3050);
PAINT GREEN (-2525 3050);
DISPLAY INVISIBLE (-2525 3050);
FORCEPROP 1 LAST PATH I65
J 0
(-2852 3175);
DISPLAY 0.872340 (-2852 3175);
PAINT GREEN (-2852 3175);
DISPLAY INVISIBLE (-2852 3175);
FORCEADD TAP..1
(-2850 3275);
FORCEPROP 3 LASTPIN (-2900 3275) SIG_NAME P3E_CPU0_PE3_OCP_TXN<15>
J 0
(-2890 3285);
DISPLAY 0.659574 (-2890 3285);
PAINT MONO (-2890 3285);
DISPLAY INVISIBLE (-2890 3285);
FORCEPROP 1 LASTPIN (-2900 3275) BN 15
J 0
(-2912 3283);
DISPLAY 0.617021 (-2912 3283);
PAINT PINK (-2912 3283);
FORCEPROP 2 LAST CDS_LIB mstr_standard
J 2
(-2850 3275);
PAINT MONO (-2850 3275);
DISPLAY INVISIBLE (-2850 3275);
FORCEPROP 1 LAST BODY_TYPE PLUMBING
J 0
(-2850 3325);
DISPLAY 1.446809 (-2850 3325);
PAINT GREEN (-2850 3325);
DISPLAY INVISIBLE (-2850 3325);
FORCEPROP 1 LAST HDL_TAP TRUE
J 0
(-2525 3150);
DISPLAY 1.446809 (-2525 3150);
PAINT GREEN (-2525 3150);
DISPLAY INVISIBLE (-2525 3150);
FORCEPROP 1 LAST PATH I66
J 0
(-2852 3275);
DISPLAY 0.872340 (-2852 3275);
PAINT GREEN (-2852 3275);
DISPLAY INVISIBLE (-2852 3275);
FORCEADD TAP..1
(-2850 3225);
FORCEPROP 3 LASTPIN (-2900 3225) SIG_NAME P3E_CPU0_PE3_OCP_TXN<14>
J 0
(-2890 3235);
DISPLAY 0.659574 (-2890 3235);
PAINT MONO (-2890 3235);
DISPLAY INVISIBLE (-2890 3235);
FORCEPROP 1 LASTPIN (-2900 3225) BN 14
J 0
(-2912 3233);
DISPLAY 0.617021 (-2912 3233);
PAINT PINK (-2912 3233);
FORCEPROP 2 LAST CDS_LIB mstr_standard
J 2
(-2850 3225);
PAINT MONO (-2850 3225);
DISPLAY INVISIBLE (-2850 3225);
FORCEPROP 1 LAST BODY_TYPE PLUMBING
J 0
(-2850 3275);
DISPLAY 1.446809 (-2850 3275);
PAINT GREEN (-2850 3275);
DISPLAY INVISIBLE (-2850 3275);
FORCEPROP 1 LAST HDL_TAP TRUE
J 0
(-2525 3100);
DISPLAY 1.446809 (-2525 3100);
PAINT GREEN (-2525 3100);
DISPLAY INVISIBLE (-2525 3100);
FORCEPROP 1 LAST PATH I67
J 0
(-2852 3225);
DISPLAY 0.872340 (-2852 3225);
PAINT GREEN (-2852 3225);
DISPLAY INVISIBLE (-2852 3225);
FORCEADD OFFPAGE..2
(-1575 3500);
FORCEPROP 2 LAST $XR0 106 
J 0
(-1386 3500);
DISPLAY 0.638298 (-1386 3500);
PAINT MONO (-1386 3500);
FORCEPROP 2 LAST CDS_LIB mstr_standard
J 0
(-1575 3500);
PAINT MONO (-1575 3500);
DISPLAY INVISIBLE (-1575 3500);
FORCEPROP 1 LAST OFFPAGE TRUE
J 0
(-1250 3375);
DISPLAY 1.170213 (-1250 3375);
PAINT GREEN (-1250 3375);
DISPLAY INVISIBLE (-1250 3375);
FORCEPROP 1 LAST COMMENT_BODY TRUE
J 0
(-1620 3405);
DISPLAY 1.170213 (-1620 3405);
PAINT GREEN (-1620 3405);
DISPLAY INVISIBLE (-1620 3405);
FORCEPROP 2 LAST PATH I68
J 0
(-1400 3575);
DISPLAY 1.021277 (-1400 3575);
PAINT ORANGE (-1400 3575);
DISPLAY INVISIBLE (-1400 3575);
FORCEADD OFFPAGE..2
(-1575 3625);
FORCEPROP 2 LAST $XR0 106 
J 0
(-1386 3625);
DISPLAY 0.638298 (-1386 3625);
PAINT MONO (-1386 3625);
FORCEPROP 2 LAST CDS_LIB mstr_standard
J 0
(-1575 3625);
PAINT MONO (-1575 3625);
DISPLAY INVISIBLE (-1575 3625);
FORCEPROP 1 LAST OFFPAGE TRUE
J 0
(-1250 3500);
DISPLAY 1.170213 (-1250 3500);
PAINT GREEN (-1250 3500);
DISPLAY INVISIBLE (-1250 3500);
FORCEPROP 1 LAST COMMENT_BODY TRUE
J 0
(-1620 3530);
DISPLAY 1.170213 (-1620 3530);
PAINT GREEN (-1620 3530);
DISPLAY INVISIBLE (-1620 3530);
FORCEPROP 2 LAST PATH I69
J 0
(-1400 3700);
DISPLAY 1.021277 (-1400 3700);
PAINT ORANGE (-1400 3700);
DISPLAY INVISIBLE (-1400 3700);
FORCEADD TAP..1
R 2
(-5875 1875);
FORCEPROP 3 LASTPIN (-5825 1875) SIG_NAME P3E_CPU0_PE3_OCP_RXP<0>
J 0
(-5815 1885);
DISPLAY 0.659574 (-5815 1885);
PAINT MONO (-5815 1885);
DISPLAY INVISIBLE (-5815 1885);
FORCEPROP 1 LASTPIN (-5825 1875) BN 0
J 2
(-5813 1883);
DISPLAY 0.617021 (-5813 1883);
PAINT PINK (-5813 1883);
FORCEPROP 2 LAST CDS_LIB mstr_standard
J 0
(-5875 1875);
PAINT MONO (-5875 1875);
DISPLAY INVISIBLE (-5875 1875);
FORCEPROP 1 LAST BODY_TYPE PLUMBING
J 2
(-5875 1925);
DISPLAY 1.446809 (-5875 1925);
PAINT GREEN (-5875 1925);
DISPLAY INVISIBLE (-5875 1925);
FORCEPROP 1 LAST HDL_TAP TRUE
J 2
(-6200 1750);
DISPLAY 1.446809 (-6200 1750);
PAINT GREEN (-6200 1750);
DISPLAY INVISIBLE (-6200 1750);
FORCEPROP 1 LAST PATH I7
J 2
(-5873 1875);
DISPLAY 0.872340 (-5873 1875);
PAINT GREEN (-5873 1875);
DISPLAY INVISIBLE (-5873 1875);
FORCEADD TAP..1
R 2
(-5875 1925);
FORCEPROP 3 LASTPIN (-5825 1925) SIG_NAME P3E_CPU0_PE3_OCP_RXP<1>
J 0
(-5815 1935);
DISPLAY 0.659574 (-5815 1935);
PAINT MONO (-5815 1935);
DISPLAY INVISIBLE (-5815 1935);
FORCEPROP 1 LASTPIN (-5825 1925) BN 1
J 2
(-5813 1933);
DISPLAY 0.617021 (-5813 1933);
PAINT PINK (-5813 1933);
FORCEPROP 2 LAST CDS_LIB mstr_standard
J 0
(-5875 1925);
PAINT MONO (-5875 1925);
DISPLAY INVISIBLE (-5875 1925);
FORCEPROP 1 LAST BODY_TYPE PLUMBING
J 2
(-5875 1975);
DISPLAY 1.446809 (-5875 1975);
PAINT GREEN (-5875 1975);
DISPLAY INVISIBLE (-5875 1975);
FORCEPROP 1 LAST HDL_TAP TRUE
J 2
(-6200 1800);
DISPLAY 1.446809 (-6200 1800);
PAINT GREEN (-6200 1800);
DISPLAY INVISIBLE (-6200 1800);
FORCEPROP 1 LAST PATH I8
J 2
(-5873 1925);
DISPLAY 0.872340 (-5873 1925);
PAINT GREEN (-5873 1925);
DISPLAY INVISIBLE (-5873 1925);
FORCEADD TAP..6
(-5875 2525);
FORCEPROP 3 LASTPIN (-5825 2525) SIG_NAME P3E_CPU0_PE3_OCP_RXP<7>
J 0
(-5815 2535);
DISPLAY 0.659574 (-5815 2535);
PAINT MONO (-5815 2535);
DISPLAY INVISIBLE (-5815 2535);
FORCEPROP 1 LASTPIN (-5825 2525) BN 7
J 0
(-5877 2533);
DISPLAY 0.617021 (-5877 2533);
PAINT GREEN (-5877 2533);
FORCEPROP 2 LAST CDS_LIB mstr_standard
J 0
(-5875 2525);
PAINT MONO (-5875 2525);
DISPLAY INVISIBLE (-5875 2525);
FORCEPROP 1 LAST BODY_TYPE PLUMBING
J 0
(-5875 2475);
DISPLAY 0.872340 (-5875 2475);
PAINT GREEN (-5875 2475);
DISPLAY INVISIBLE (-5875 2475);
FORCEPROP 1 LAST HDL_TAP TRUE
J 0
(-5550 2400);
DISPLAY 0.872340 (-5550 2400);
PAINT ORANGE (-5550 2400);
DISPLAY INVISIBLE (-5550 2400);
FORCEPROP 1 LAST PATH I81
J 0
(-5877 2525);
DISPLAY 0.872340 (-5877 2525);
PAINT GREEN (-5877 2525);
DISPLAY INVISIBLE (-5877 2525);
FORCEADD TAP..6
(-5875 2475);
FORCEPROP 3 LASTPIN (-5825 2475) SIG_NAME P3E_CPU0_PE3_OCP_RXP<6>
J 0
(-5815 2485);
DISPLAY 0.659574 (-5815 2485);
PAINT MONO (-5815 2485);
DISPLAY INVISIBLE (-5815 2485);
FORCEPROP 1 LASTPIN (-5825 2475) BN 6
J 0
(-5877 2483);
DISPLAY 0.617021 (-5877 2483);
PAINT GREEN (-5877 2483);
FORCEPROP 2 LAST CDS_LIB mstr_standard
J 0
(-5875 2475);
PAINT MONO (-5875 2475);
DISPLAY INVISIBLE (-5875 2475);
FORCEPROP 1 LAST BODY_TYPE PLUMBING
J 0
(-5875 2425);
DISPLAY 0.872340 (-5875 2425);
PAINT GREEN (-5875 2425);
DISPLAY INVISIBLE (-5875 2425);
FORCEPROP 1 LAST HDL_TAP TRUE
J 0
(-5550 2350);
DISPLAY 0.872340 (-5550 2350);
PAINT ORANGE (-5550 2350);
DISPLAY INVISIBLE (-5550 2350);
FORCEPROP 1 LAST PATH I82
J 0
(-5877 2475);
DISPLAY 0.872340 (-5877 2475);
PAINT GREEN (-5877 2475);
DISPLAY INVISIBLE (-5877 2475);
FORCEADD TAP..6
(-5875 2425);
FORCEPROP 3 LASTPIN (-5825 2425) SIG_NAME P3E_CPU0_PE3_OCP_RXP<5>
J 0
(-5815 2435);
DISPLAY 0.659574 (-5815 2435);
PAINT MONO (-5815 2435);
DISPLAY INVISIBLE (-5815 2435);
FORCEPROP 1 LASTPIN (-5825 2425) BN 5
J 0
(-5877 2433);
DISPLAY 0.617021 (-5877 2433);
PAINT GREEN (-5877 2433);
FORCEPROP 2 LAST CDS_LIB mstr_standard
J 0
(-5875 2425);
PAINT MONO (-5875 2425);
DISPLAY INVISIBLE (-5875 2425);
FORCEPROP 1 LAST BODY_TYPE PLUMBING
J 0
(-5875 2375);
DISPLAY 0.872340 (-5875 2375);
PAINT GREEN (-5875 2375);
DISPLAY INVISIBLE (-5875 2375);
FORCEPROP 1 LAST HDL_TAP TRUE
J 0
(-5550 2300);
DISPLAY 0.872340 (-5550 2300);
PAINT ORANGE (-5550 2300);
DISPLAY INVISIBLE (-5550 2300);
FORCEPROP 1 LAST PATH I83
J 0
(-5877 2425);
DISPLAY 0.872340 (-5877 2425);
PAINT GREEN (-5877 2425);
DISPLAY INVISIBLE (-5877 2425);
FORCEADD TAP..6
(-5875 2375);
FORCEPROP 3 LASTPIN (-5825 2375) SIG_NAME P3E_CPU0_PE3_OCP_RXP<4>
J 0
(-5815 2385);
DISPLAY 0.659574 (-5815 2385);
PAINT MONO (-5815 2385);
DISPLAY INVISIBLE (-5815 2385);
FORCEPROP 1 LASTPIN (-5825 2375) BN 4
J 0
(-5877 2383);
DISPLAY 0.617021 (-5877 2383);
PAINT GREEN (-5877 2383);
FORCEPROP 2 LAST CDS_LIB mstr_standard
J 0
(-5875 2375);
PAINT MONO (-5875 2375);
DISPLAY INVISIBLE (-5875 2375);
FORCEPROP 1 LAST BODY_TYPE PLUMBING
J 0
(-5875 2325);
DISPLAY 0.872340 (-5875 2325);
PAINT GREEN (-5875 2325);
DISPLAY INVISIBLE (-5875 2325);
FORCEPROP 1 LAST HDL_TAP TRUE
J 0
(-5550 2250);
DISPLAY 0.872340 (-5550 2250);
PAINT ORANGE (-5550 2250);
DISPLAY INVISIBLE (-5550 2250);
FORCEPROP 1 LAST PATH I84
J 0
(-5877 2375);
DISPLAY 0.872340 (-5877 2375);
PAINT GREEN (-5877 2375);
DISPLAY INVISIBLE (-5877 2375);
FORCEADD TAP..6
(-6025 2275);
FORCEPROP 3 LASTPIN (-5975 2275) SIG_NAME P3E_CPU0_PE3_OCP_RXN<7>
J 0
(-5965 2285);
DISPLAY 0.659574 (-5965 2285);
PAINT MONO (-5965 2285);
DISPLAY INVISIBLE (-5965 2285);
FORCEPROP 1 LASTPIN (-5975 2275) BN 7
J 0
(-6027 2283);
DISPLAY 0.617021 (-6027 2283);
PAINT GREEN (-6027 2283);
FORCEPROP 2 LAST CDS_LIB mstr_standard
J 0
(-6025 2275);
PAINT MONO (-6025 2275);
DISPLAY INVISIBLE (-6025 2275);
FORCEPROP 1 LAST BODY_TYPE PLUMBING
J 0
(-6025 2225);
DISPLAY 0.872340 (-6025 2225);
PAINT GREEN (-6025 2225);
DISPLAY INVISIBLE (-6025 2225);
FORCEPROP 1 LAST HDL_TAP TRUE
J 0
(-5700 2150);
DISPLAY 0.872340 (-5700 2150);
PAINT ORANGE (-5700 2150);
DISPLAY INVISIBLE (-5700 2150);
FORCEPROP 1 LAST PATH I85
J 0
(-6027 2275);
DISPLAY 0.872340 (-6027 2275);
PAINT GREEN (-6027 2275);
DISPLAY INVISIBLE (-6027 2275);
FORCEADD TAP..6
(-6025 2225);
FORCEPROP 3 LASTPIN (-5975 2225) SIG_NAME P3E_CPU0_PE3_OCP_RXN<6>
J 0
(-5965 2235);
DISPLAY 0.659574 (-5965 2235);
PAINT MONO (-5965 2235);
DISPLAY INVISIBLE (-5965 2235);
FORCEPROP 1 LASTPIN (-5975 2225) BN 6
J 0
(-6027 2233);
DISPLAY 0.617021 (-6027 2233);
PAINT GREEN (-6027 2233);
FORCEPROP 2 LAST CDS_LIB mstr_standard
J 0
(-6025 2225);
PAINT MONO (-6025 2225);
DISPLAY INVISIBLE (-6025 2225);
FORCEPROP 1 LAST BODY_TYPE PLUMBING
J 0
(-6025 2175);
DISPLAY 0.872340 (-6025 2175);
PAINT GREEN (-6025 2175);
DISPLAY INVISIBLE (-6025 2175);
FORCEPROP 1 LAST HDL_TAP TRUE
J 0
(-5700 2100);
DISPLAY 0.872340 (-5700 2100);
PAINT ORANGE (-5700 2100);
DISPLAY INVISIBLE (-5700 2100);
FORCEPROP 1 LAST PATH I86
J 0
(-6027 2225);
DISPLAY 0.872340 (-6027 2225);
PAINT GREEN (-6027 2225);
DISPLAY INVISIBLE (-6027 2225);
FORCEADD TAP..6
(-6025 2175);
FORCEPROP 3 LASTPIN (-5975 2175) SIG_NAME P3E_CPU0_PE3_OCP_RXN<5>
J 0
(-5965 2185);
DISPLAY 0.659574 (-5965 2185);
PAINT MONO (-5965 2185);
DISPLAY INVISIBLE (-5965 2185);
FORCEPROP 1 LASTPIN (-5975 2175) BN 5
J 0
(-6027 2183);
DISPLAY 0.617021 (-6027 2183);
PAINT GREEN (-6027 2183);
FORCEPROP 2 LAST CDS_LIB mstr_standard
J 0
(-6025 2175);
PAINT MONO (-6025 2175);
DISPLAY INVISIBLE (-6025 2175);
FORCEPROP 1 LAST BODY_TYPE PLUMBING
J 0
(-6025 2125);
DISPLAY 0.872340 (-6025 2125);
PAINT GREEN (-6025 2125);
DISPLAY INVISIBLE (-6025 2125);
FORCEPROP 1 LAST HDL_TAP TRUE
J 0
(-5700 2050);
DISPLAY 0.872340 (-5700 2050);
PAINT ORANGE (-5700 2050);
DISPLAY INVISIBLE (-5700 2050);
FORCEPROP 1 LAST PATH I87
J 0
(-6027 2175);
DISPLAY 0.872340 (-6027 2175);
PAINT GREEN (-6027 2175);
DISPLAY INVISIBLE (-6027 2175);
FORCEADD TAP..6
(-6025 2125);
FORCEPROP 3 LASTPIN (-5975 2125) SIG_NAME P3E_CPU0_PE3_OCP_RXN<4>
J 0
(-5965 2135);
DISPLAY 0.659574 (-5965 2135);
PAINT MONO (-5965 2135);
DISPLAY INVISIBLE (-5965 2135);
FORCEPROP 1 LASTPIN (-5975 2125) BN 4
J 0
(-6027 2133);
DISPLAY 0.617021 (-6027 2133);
PAINT GREEN (-6027 2133);
FORCEPROP 2 LAST CDS_LIB mstr_standard
J 0
(-6025 2125);
PAINT MONO (-6025 2125);
DISPLAY INVISIBLE (-6025 2125);
FORCEPROP 1 LAST BODY_TYPE PLUMBING
J 0
(-6025 2075);
DISPLAY 0.872340 (-6025 2075);
PAINT GREEN (-6025 2075);
DISPLAY INVISIBLE (-6025 2075);
FORCEPROP 1 LAST HDL_TAP TRUE
J 0
(-5700 2000);
DISPLAY 0.872340 (-5700 2000);
PAINT ORANGE (-5700 2000);
DISPLAY INVISIBLE (-5700 2000);
FORCEPROP 1 LAST PATH I88
J 0
(-6027 2125);
DISPLAY 0.872340 (-6027 2125);
PAINT GREEN (-6027 2125);
DISPLAY INVISIBLE (-6027 2125);
FORCEADD SKX_EXT_B..12
(-4200 2575);
FORCEPROP 1 LAST LOCATION U5D1
J 0
(-4900 3775);
DISPLAY 0.617021 (-4900 3775);
PAINT AQUA (-4900 3775);
FORCEPROP 1 LAST PART_NUMBER TBD
J 0
(-4900 1425);
DISPLAY 0.617021 (-4900 1425);
PAINT BLUE (-4900 1425);
FORCEPROP 1 LAST MATERIAL IC
J 0
(-4900 3725);
DISPLAY 0.617021 (-4900 3725);
PAINT SKYBLUE (-4900 3725);
FORCEPROP 2 LASTPIN (-3450 3525) $PN CV5
J 0
(-3440 3535);
DISPLAY 0.617021 (-3440 3535);
PAINT ORANGE (-3440 3535);
FORCEPROP 2 LASTPIN (-3450 3475) $PN DA4
J 0
(-3440 3485);
DISPLAY 0.617021 (-3440 3485);
PAINT ORANGE (-3440 3485);
FORCEPROP 2 LASTPIN (-3450 3425) $PN DC6
J 0
(-3440 3435);
DISPLAY 0.617021 (-3440 3435);
PAINT ORANGE (-3440 3435);
FORCEPROP 2 LASTPIN (-3450 3375) $PN DG6
J 0
(-3440 3385);
DISPLAY 0.617021 (-3440 3385);
PAINT ORANGE (-3440 3385);
FORCEPROP 2 LASTPIN (-3450 2975) $PN DK5
J 0
(-3440 2985);
DISPLAY 0.617021 (-3440 2985);
PAINT ORANGE (-3440 2985);
FORCEPROP 2 LASTPIN (-3450 2925) $PN DM5
J 0
(-3440 2935);
DISPLAY 0.617021 (-3440 2935);
PAINT ORANGE (-3440 2935);
FORCEPROP 2 LASTPIN (-3450 2875) $PN DN6
J 0
(-3440 2885);
DISPLAY 0.617021 (-3440 2885);
PAINT ORANGE (-3440 2885);
FORCEPROP 2 LASTPIN (-3450 2425) $PN DV9
J 0
(-3440 2435);
DISPLAY 0.617021 (-3440 2435);
PAINT ORANGE (-3440 2435);
FORCEPROP 2 LASTPIN (-3450 2375) $PN DY9
J 0
(-3440 2385);
DISPLAY 0.617021 (-3440 2385);
PAINT ORANGE (-3440 2385);
FORCEPROP 2 LASTPIN (-3450 2025) $PN EA10
J 0
(-3440 2035);
DISPLAY 0.617021 (-3440 2035);
PAINT ORANGE (-3440 2035);
FORCEPROP 2 LASTPIN (-3450 1975) $PN EB11
J 0
(-3440 1985);
DISPLAY 0.617021 (-3440 1985);
PAINT ORANGE (-3440 1985);
FORCEPROP 2 LASTPIN (-3450 1925) $PN ED13
J 0
(-3440 1935);
DISPLAY 0.617021 (-3440 1935);
PAINT ORANGE (-3440 1935);
FORCEPROP 2 LASTPIN (-3450 1875) $PN EC14
J 0
(-3440 1885);
DISPLAY 0.617021 (-3440 1885);
PAINT ORANGE (-3440 1885);
FORCEPROP 2 LASTPIN (-3450 3275) $PN CY5
J 0
(-3440 3285);
DISPLAY 0.617021 (-3440 3285);
PAINT ORANGE (-3440 3285);
FORCEPROP 2 LASTPIN (-3450 3225) $PN DB5
J 0
(-3440 3235);
DISPLAY 0.617021 (-3440 3235);
PAINT ORANGE (-3440 3235);
FORCEPROP 2 LASTPIN (-3450 3175) $PN DD5
J 0
(-3440 3185);
DISPLAY 0.617021 (-3440 3185);
PAINT ORANGE (-3440 3185);
FORCEPROP 2 LASTPIN (-3450 3125) $PN DJ6
J 0
(-3440 3135);
DISPLAY 0.617021 (-3440 3135);
PAINT ORANGE (-3440 3135);
FORCEPROP 2 LASTPIN (-3450 2775) $PN DJ4
J 0
(-3440 2785);
DISPLAY 0.617021 (-3440 2785);
PAINT ORANGE (-3440 2785);
FORCEPROP 2 LASTPIN (-3450 2675) $PN DP5
J 0
(-3440 2685);
DISPLAY 0.617021 (-3440 2685);
PAINT ORANGE (-3440 2685);
FORCEPROP 2 LASTPIN (-3450 2625) $PN DM7
J 0
(-3440 2635);
DISPLAY 0.617021 (-3440 2635);
PAINT ORANGE (-3440 2635);
FORCEPROP 2 LASTPIN (-3450 2275) $PN DR8
J 0
(-3440 2285);
DISPLAY 0.617021 (-3440 2285);
PAINT ORANGE (-3440 2285);
FORCEPROP 2 LASTPIN (-3450 2225) $PN DU8
J 0
(-3440 2235);
DISPLAY 0.617021 (-3440 2235);
PAINT ORANGE (-3440 2235);
FORCEPROP 2 LASTPIN (-3450 2175) $PN DW10
J 0
(-3440 2185);
DISPLAY 0.617021 (-3440 2185);
PAINT ORANGE (-3440 2185);
FORCEPROP 2 LASTPIN (-3450 2125) $PN EB9
J 0
(-3440 2135);
DISPLAY 0.617021 (-3440 2135);
PAINT ORANGE (-3440 2135);
FORCEPROP 2 LASTPIN (-3450 1775) $PN DY11
J 0
(-3440 1785);
DISPLAY 0.617021 (-3440 1785);
PAINT ORANGE (-3440 1785);
FORCEPROP 2 LASTPIN (-3450 1725) $PN EC12
J 0
(-3440 1735);
DISPLAY 0.617021 (-3440 1735);
PAINT ORANGE (-3440 1735);
FORCEPROP 2 LASTPIN (-3450 1675) $PN EE12
J 0
(-3440 1685);
DISPLAY 0.617021 (-3440 1685);
PAINT ORANGE (-3440 1685);
FORCEPROP 2 LASTPIN (-3450 1625) $PN EE14
J 0
(-3440 1635);
DISPLAY 0.617021 (-3440 1635);
PAINT ORANGE (-3440 1635);
FORCEPROP 2 LASTPIN (-4950 3525) $PN CU10
J 2
(-4960 3535);
DISPLAY 0.617021 (-4960 3535);
PAINT ORANGE (-4960 3535);
FORCEPROP 2 LASTPIN (-4950 3475) $PN CW10
J 2
(-4960 3485);
DISPLAY 0.617021 (-4960 3485);
PAINT ORANGE (-4960 3485);
FORCEPROP 2 LASTPIN (-4950 3425) $PN DA12
J 2
(-4960 3435);
DISPLAY 0.617021 (-4960 3435);
PAINT ORANGE (-4960 3435);
FORCEPROP 2 LASTPIN (-4950 3375) $PN DC12
J 2
(-4960 3385);
DISPLAY 0.617021 (-4960 3385);
PAINT ORANGE (-4960 3385);
FORCEPROP 2 LASTPIN (-4950 3025) $PN DF11
J 2
(-4960 3035);
DISPLAY 0.617021 (-4960 3035);
PAINT ORANGE (-4960 3035);
FORCEPROP 2 LASTPIN (-4950 2975) $PN DE12
J 2
(-4960 2985);
DISPLAY 0.617021 (-4960 2985);
PAINT ORANGE (-4960 2985);
FORCEPROP 2 LASTPIN (-4950 2925) $PN DH11
J 2
(-4960 2935);
DISPLAY 0.617021 (-4960 2935);
PAINT ORANGE (-4960 2935);
FORCEPROP 2 LASTPIN (-4950 2875) $PN DK13
J 2
(-4960 2885);
DISPLAY 0.617021 (-4960 2885);
PAINT ORANGE (-4960 2885);
FORCEPROP 2 LASTPIN (-4950 2525) $PN DJ14
J 2
(-4960 2535);
DISPLAY 0.617021 (-4960 2535);
PAINT ORANGE (-4960 2535);
FORCEPROP 2 LASTPIN (-4950 2475) $PN DM13
J 2
(-4960 2485);
DISPLAY 0.617021 (-4960 2485);
PAINT ORANGE (-4960 2485);
FORCEPROP 2 LASTPIN (-4950 2425) $PN DP15
J 2
(-4960 2435);
DISPLAY 0.617021 (-4960 2435);
PAINT ORANGE (-4960 2435);
FORCEPROP 2 LASTPIN (-4950 2375) $PN DN16
J 2
(-4960 2385);
DISPLAY 0.617021 (-4960 2385);
PAINT ORANGE (-4960 2385);
FORCEPROP 2 LASTPIN (-4950 2025) $PN DR18
J 2
(-4960 2035);
DISPLAY 0.617021 (-4960 2035);
PAINT ORANGE (-4960 2035);
FORCEPROP 2 LASTPIN (-4950 1975) $PN DV17
J 2
(-4960 1985);
DISPLAY 0.617021 (-4960 1985);
PAINT ORANGE (-4960 1985);
FORCEPROP 2 LASTPIN (-4950 1925) $PN DU18
J 2
(-4960 1935);
DISPLAY 0.617021 (-4960 1935);
PAINT ORANGE (-4960 1935);
FORCEPROP 2 LASTPIN (-4950 1875) $PN DY17
J 2
(-4960 1885);
DISPLAY 0.617021 (-4960 1885);
PAINT ORANGE (-4960 1885);
FORCEPROP 2 LASTPIN (-4950 3275) $PN CV9
J 2
(-4960 3285);
DISPLAY 0.617021 (-4960 3285);
PAINT ORANGE (-4960 3285);
FORCEPROP 2 LASTPIN (-4950 3225) $PN CY11
J 2
(-4960 3235);
DISPLAY 0.617021 (-4960 3235);
PAINT ORANGE (-4960 3235);
FORCEPROP 2 LASTPIN (-4950 3175) $PN DB11
J 2
(-4960 3185);
DISPLAY 0.617021 (-4960 3185);
PAINT ORANGE (-4960 3185);
FORCEPROP 2 LASTPIN (-4950 3125) $PN DD13
J 2
(-4960 3135);
DISPLAY 0.617021 (-4960 3135);
PAINT ORANGE (-4960 3135);
FORCEPROP 2 LASTPIN (-4950 2775) $PN DG10
J 2
(-4960 2785);
DISPLAY 0.617021 (-4960 2785);
PAINT ORANGE (-4960 2785);
FORCEPROP 2 LASTPIN (-4950 2725) $PN DG12
J 2
(-4960 2735);
DISPLAY 0.617021 (-4960 2735);
PAINT ORANGE (-4960 2735);
FORCEPROP 2 LASTPIN (-4950 2675) $PN DJ12
J 2
(-4960 2685);
DISPLAY 0.617021 (-4960 2685);
PAINT ORANGE (-4960 2685);
FORCEPROP 2 LASTPIN (-4950 2625) $PN DL12
J 2
(-4960 2635);
DISPLAY 0.617021 (-4960 2635);
PAINT ORANGE (-4960 2635);
FORCEPROP 2 LASTPIN (-4950 2225) $PN DN14
J 2
(-4960 2235);
DISPLAY 0.617021 (-4960 2235);
PAINT ORANGE (-4960 2235);
FORCEPROP 2 LASTPIN (-4950 2175) $PN DR14
J 2
(-4960 2185);
DISPLAY 0.617021 (-4960 2185);
PAINT ORANGE (-4960 2185);
FORCEPROP 2 LASTPIN (-4950 2125) $PN DR16
J 2
(-4960 2135);
DISPLAY 0.617021 (-4960 2135);
PAINT ORANGE (-4960 2135);
FORCEPROP 2 LASTPIN (-4950 1775) $PN DT19
J 2
(-4960 1785);
DISPLAY 0.617021 (-4960 1785);
PAINT ORANGE (-4960 1785);
FORCEPROP 2 LASTPIN (-4950 1725) $PN DW16
J 2
(-4960 1735);
DISPLAY 0.617021 (-4960 1735);
PAINT ORANGE (-4960 1735);
FORCEPROP 2 LASTPIN (-4950 1675) $PN DW18
J 2
(-4960 1685);
DISPLAY 0.617021 (-4960 1685);
PAINT ORANGE (-4960 1685);
FORCEPROP 2 LASTPIN (-4950 1625) $PN EA18
J 2
(-4960 1635);
DISPLAY 0.617021 (-4960 1635);
PAINT ORANGE (-4960 1635);
FORCEPROP 2 LASTPIN (-3450 2525) $PN DP7
J 0
(-3440 2535);
DISPLAY 0.617021 (-3440 2535);
PAINT ORANGE (-3440 2535);
FORCEPROP 2 LASTPIN (-3450 2475) $PN DT9
J 0
(-3440 2485);
DISPLAY 0.617021 (-3440 2485);
PAINT ORANGE (-3440 2485);
FORCEPROP 2 LASTPIN (-3450 2725) $PN DL6
J 0
(-3440 2735);
DISPLAY 0.617021 (-3440 2735);
PAINT ORANGE (-3440 2735);
FORCEPROP 2 LASTPIN (-4950 2275) $PN DL14
J 2
(-4960 2285);
DISPLAY 0.617021 (-4960 2285);
PAINT ORANGE (-4960 2285);
FORCEPROP 2 LASTPIN (-3450 3025) $PN DH5
J 0
(-3440 3035);
DISPLAY 0.617021 (-3440 3035);
PAINT ORANGE (-3440 3035);
FORCEPROP 1 LAST PACK_TYPE BGA1
J 0
(-4900 3825);
PAINT SKYBLUE (-4900 3825);
DISPLAY INVISIBLE (-4900 3825);
FORCEPROP 2 LAST CDS_LIB chpset_lib
J 0
(-4200 2575);
PAINT ORANGE (-4200 2575);
DISPLAY INVISIBLE (-4200 2575);
FORCEPROP 2 LAST SEC_TYPE BGA1
J 0
(-4900 3825);
DISPLAY 1.021277 (-4900 3825);
PAINT ORANGE (-4900 3825);
DISPLAY INVISIBLE (-4900 3825);
FORCEPROP 2 LAST SEC 12
J 0
(-4900 3825);
DISPLAY 0.680851 (-4900 3825);
PAINT MONO (-4900 3825);
DISPLAY INVISIBLE (-4900 3825);
FORCEPROP 2 LAST CDS_LOCATION U5D1
J 0
(-4900 3775);
DISPLAY 0.617021 (-4900 3775);
PAINT AQUA (-4900 3775);
DISPLAY INVISIBLE (-4900 3775);
FORCEPROP 1 LAST PATH I89
J 0
(-4200 3725);
PAINT GREEN (-4200 3725);
DISPLAY INVISIBLE (-4200 3725);
FORCEADD TAP..1
R 2
(-5875 1975);
FORCEPROP 3 LASTPIN (-5825 1975) SIG_NAME P3E_CPU0_PE3_OCP_RXP<2>
J 0
(-5815 1985);
DISPLAY 0.659574 (-5815 1985);
PAINT MONO (-5815 1985);
DISPLAY INVISIBLE (-5815 1985);
FORCEPROP 1 LASTPIN (-5825 1975) BN 2
J 2
(-5813 1983);
DISPLAY 0.617021 (-5813 1983);
PAINT PINK (-5813 1983);
FORCEPROP 2 LAST CDS_LIB mstr_standard
J 0
(-5875 1975);
PAINT MONO (-5875 1975);
DISPLAY INVISIBLE (-5875 1975);
FORCEPROP 1 LAST BODY_TYPE PLUMBING
J 2
(-5875 2025);
DISPLAY 1.446809 (-5875 2025);
PAINT GREEN (-5875 2025);
DISPLAY INVISIBLE (-5875 2025);
FORCEPROP 1 LAST HDL_TAP TRUE
J 2
(-6200 1850);
DISPLAY 1.446809 (-6200 1850);
PAINT GREEN (-6200 1850);
DISPLAY INVISIBLE (-6200 1850);
FORCEPROP 1 LAST PATH I9
J 2
(-5873 1975);
DISPLAY 0.872340 (-5873 1975);
PAINT GREEN (-5873 1975);
DISPLAY INVISIBLE (-5873 1975);
FORCEADD DESIGN_NOTE..1
(-4700 1325);
FORCEPROP 0 LAST L1 CPU SYMBOLS 1-30 ARE PRELIMINARY AND SUBJECT TO CHANGE
J 0
(-4900 1200);
DISPLAY 1.021277 (-4900 1200);
PAINT ORANGE (-4900 1200);
FORCEPROP 2 LAST CDS_LIB mstr_symbols
J 0
(-4700 1325);
PAINT ORANGE (-4700 1325);
DISPLAY INVISIBLE (-4700 1325);
FORCEPROP 1 LAST COMMENT_BODY TRUE
J 0
(-4675 1425);
DISPLAY 0.978723 (-4675 1425);
PAINT ORANGE (-4675 1425);
DISPLAY INVISIBLE (-4675 1425);
FORCEADD PRELIM..10
(-4190 2565);
PAINT GRAY (-4190 2565);
FORCEPROP 2 LAST CDS_LIB mstr_misc
J 0
(-4190 2565);
PAINT ORANGE (-4190 2565);
DISPLAY INVISIBLE (-4190 2565);
FORCEPROP 1 LAST COMMENT_BODY TRUE
J 0
(-4190 2565);
PAINT ORANGE (-4190 2565);
DISPLAY INVISIBLE (-4190 2565);
FORCEADD INTEL_CORP_BPAGE..1
(0 0);
FORCEPROP 1 LAST CDS_CON_LAST_MODIFIED Fri Jun 16 17:48:12 2017
J 0
(-1425 325);
DISPLAY 1.340426 (-1425 325);
PAINT GREEN (-1425 325);
DISPLAY INVISIBLE (-1425 325);
FORCEPROP 1 LAST CUSTOM_TXT_CDS <CURRENT_DESIGN_SHEET> OF <TOTAL_DESIGN_SHEETS>
J 0
(-500 25);
PAINT ORANGE (-500 25);
FORCEPROP 1 LAST CUSTOM_TXT_CDS <CON_LAST_MODIFIED>
J 0
(-4000 100);
PAINT ORANGE (-4000 100);
FORCEPROP 2 LAST CUSTOM_TXT_CDS <XR_PAGE_TITLE>
J 0
(-7890 5250);
DISPLAY 0.638298 (-7890 5250);
PAINT PINK (-7890 5250);
DISPLAY INVISIBLE (-7890 5250);
FORCEPROP 1 LAST SCH_TITLE SKYLAKE - SKT0 - 12 OF 21
J 0
(-7950 50);
DISPLAY 1.212766 (-7950 50);
PAINT GREEN (-7950 50);
FORCEPROP 2 LAST PAGE_BORDER TRUE
J 0
(-7890 5250);
DISPLAY 0.851064 (-7890 5250);
PAINT PINK (-7890 5250);
DISPLAY INVISIBLE (-7890 5250);
FORCEPROP 2 LAST CDS_LIB mstr_symbols
J 0
(0 0);
PAINT ORANGE (0 0);
DISPLAY INVISIBLE (0 0);
FORCEPROP 1 LAST COMMENT_BODY TRUE
J 0
(12 12);
DISPLAY 0.638298 (12 12);
PAINT GREEN (12 12);
DISPLAY INVISIBLE (12 12);
FORCEPROP 2 LAST CDS_XR_PAGE_TITLE CR-32 : @BASEBOARD_FAB2_LIB.BASEBOARD_FAB2(SCH_1):PAGE32
J 0
(-7890 5250);
DISPLAY 0.638298 (-7890 5250);
PAINT PINK (-7890 5250);
DISPLAY INVISIBLE (-7890 5250);
WIRE 17 -1 (-2800 1650)(-2800 1700);
WIRE 17 -1 (-2800 1700)(-2800 1750);
WIRE 17 -1 (-2800 1750)(-2800 1800);
WIRE 17 -1 (-2800 1800)(-2800 2150);
WIRE 17 -1 (-2800 2150)(-2800 2200);
WIRE 17 -1 (-2800 2200)(-2800 2250);
WIRE 17 -1 (-2800 2250)(-2800 2300);
WIRE 17 -1 (-2800 2650)(-2800 2300);
WIRE 17 -1 (-2800 2700)(-2800 2650);
WIRE 17 -1 (-2800 2700)(-2800 2750);
WIRE 17 -1 (-2800 3500)(-1625 3500);
FORCEPROP 2 LAST SIG_NAME P3E_CPU0_PE3_OCP_TXN<15:0>
J 0
(-2760 3510);
DISPLAY 0.617021 (-2760 3510);
PAINT ORANGE (-2760 3510);
WIRE 17 -1 (-2800 2750)(-2800 2800);
WIRE 17 -1 (-2800 2800)(-2800 3150);
WIRE 17 -1 (-2800 3300)(-2800 3500);
WIRE 17 -1 (-2800 3250)(-2800 3300);
WIRE 17 -1 (-2800 3150)(-2800 3200);
WIRE 17 -1 (-2800 3200)(-2800 3250);
WIRE 17 -1 (-2950 1900)(-2950 1950);
WIRE 17 -1 (-2950 1950)(-2950 2000);
WIRE 17 -1 (-2950 2000)(-2950 2050);
WIRE 17 -1 (-2950 2050)(-2950 2400);
WIRE 17 -1 (-2950 2400)(-2950 2450);
WIRE 17 -1 (-2950 2450)(-2950 2500);
WIRE 17 -1 (-2950 2500)(-2950 2550);
WIRE 17 -1 (-2950 2550)(-2950 2900);
WIRE 17 -1 (-2950 2950)(-2950 2900);
WIRE 17 -1 (-2950 2950)(-2950 3000);
WIRE 17 -1 (-2950 3000)(-2950 3050);
WIRE 17 -1 (-2950 3050)(-2950 3400);
WIRE 17 -1 (-2950 3450)(-2950 3400);
WIRE 17 -1 (-2950 3625)(-1625 3625);
FORCEPROP 2 LAST SIG_NAME P3E_CPU0_PE3_OCP_TXP<15:0>
J 0
(-2760 3635);
DISPLAY 0.617021 (-2760 3635);
PAINT ORANGE (-2760 3635);
WIRE 17 -1 (-2950 3550)(-2950 3625);
WIRE 17 -1 (-2950 3450)(-2950 3500);
WIRE 17 -1 (-2950 3500)(-2950 3550);
WIRE 17 -1 (-6075 1700)(-6075 1650);
WIRE 17 -1 (-6075 1750)(-6075 1700);
WIRE 17 -1 (-6075 1800)(-6075 1750);
WIRE 16 -1 (-6075 1800)(-6075 2150);
WIRE 17 -1 (-6075 2200)(-6075 2150);
WIRE 17 -1 (-6075 2250)(-6075 2200);
WIRE 17 -1 (-6075 2300)(-6075 2250);
WIRE 17 -1 (-6075 2650)(-6075 2300);
WIRE 17 -1 (-6075 2700)(-6075 2650);
WIRE 17 -1 (-6075 2750)(-6075 2700);
WIRE 17 -1 (-6075 2800)(-6075 2750);
WIRE 17 -1 (-7225 3500)(-6075 3500);
FORCEPROP 2 LAST SIG_NAME P3E_CPU0_PE3_OCP_RXN<15:0>
J 0
(-7185 3510);
DISPLAY 0.617021 (-7185 3510);
PAINT ORANGE (-7185 3510);
WIRE 17 -1 (-6075 3500)(-6075 3300);
WIRE 17 -1 (-6075 2800)(-6075 3150);
WIRE 17 -1 (-6075 3200)(-6075 3150);
WIRE 17 -1 (-6075 3300)(-6075 3250);
WIRE 17 -1 (-6075 3250)(-6075 3200);
WIRE 17 -1 (-5925 1950)(-5925 1900);
WIRE 17 -1 (-5925 2000)(-5925 1950);
WIRE 17 -1 (-5925 2050)(-5925 2000);
WIRE 17 -1 (-5925 2400)(-5925 2050);
WIRE 17 -1 (-5925 2450)(-5925 2400);
WIRE 17 -1 (-5925 2500)(-5925 2450);
WIRE 17 -1 (-5925 2550)(-5925 2500);
WIRE 17 -1 (-5925 2900)(-5925 2550);
WIRE 17 -1 (-5925 2950)(-5925 2900);
WIRE 17 -1 (-5925 2950)(-5925 3000);
WIRE 17 -1 (-5925 3050)(-5925 3000);
WIRE 17 -1 (-5925 3400)(-5925 3050);
WIRE 17 -1 (-7225 3625)(-5925 3625);
FORCEPROP 2 LAST SIG_NAME P3E_CPU0_PE3_OCP_RXP<15:0>
J 0
(-7185 3635);
DISPLAY 0.617021 (-7185 3635);
PAINT ORANGE (-7185 3635);
WIRE 17 -1 (-5925 3450)(-5925 3400);
WIRE 17 -1 (-5925 3500)(-5925 3450);
WIRE 17 -1 (-5925 3625)(-5925 3550);
WIRE 17 -1 (-5925 3550)(-5925 3500);
WIRE 16 -1 (-5825 3525)(-4950 3525);
WIRE 16 -1 (-5825 2925)(-4950 2925);
WIRE 16 -1 (-5825 3025)(-4950 3025);
WIRE 16 -1 (-5975 3275)(-4950 3275);
WIRE 16 -1 (-5825 2375)(-4950 2375);
WIRE 16 -1 (-5825 2425)(-4950 2425);
WIRE 16 -1 (-5825 2525)(-4950 2525);
WIRE 16 -1 (-2900 3225)(-3450 3225);
WIRE 16 -1 (-2900 3275)(-3450 3275);
WIRE 16 -1 (-2900 2775)(-3450 2775);
WIRE 16 -1 (-5975 3225)(-4950 3225);
WIRE 16 -1 (-5975 2775)(-4950 2775);
WIRE 16 -1 (-5975 2725)(-4950 2725);
WIRE 16 -1 (-5975 2675)(-4950 2675);
WIRE 16 -1 (-5975 2625)(-4950 2625);
WIRE 16 -1 (-5825 2475)(-4950 2475);
WIRE 16 -1 (-2900 2625)(-3450 2625);
WIRE 16 -1 (-2900 2675)(-3450 2675);
WIRE 16 -1 (-5975 3125)(-4950 3125);
WIRE 16 -1 (-5825 3375)(-4950 3375);
WIRE 16 -1 (-5825 2975)(-4950 2975);
WIRE 16 -1 (-5975 1625)(-4950 1625);
WIRE 16 -1 (-5975 1775)(-4950 1775);
WIRE 16 -1 (-5825 1875)(-4950 1875);
WIRE 16 -1 (-5825 1925)(-4950 1925);
WIRE 16 -1 (-5825 1975)(-4950 1975);
WIRE 16 -1 (-5825 2025)(-4950 2025);
WIRE 16 -1 (-5975 1675)(-4950 1675);
WIRE 16 -1 (-5975 1725)(-4950 1725);
WIRE 16 -1 (-5825 2875)(-4950 2875);
WIRE 16 -1 (-5825 3425)(-4950 3425);
WIRE 16 -1 (-5825 3475)(-4950 3475);
WIRE 16 -1 (-5975 2125)(-4950 2125);
WIRE 16 -1 (-5975 2175)(-4950 2175);
WIRE 16 -1 (-5975 2225)(-4950 2225);
WIRE 16 -1 (-5975 2275)(-4950 2275);
WIRE 16 -1 (-5975 3175)(-4950 3175);
WIRE 16 -1 (-3050 1875)(-3450 1875);
WIRE 16 -1 (-3050 1925)(-3450 1925);
WIRE 16 -1 (-3050 1975)(-3450 1975);
WIRE 16 -1 (-3050 2025)(-3450 2025);
WIRE 16 -1 (-2900 1625)(-3450 1625);
WIRE 16 -1 (-2900 1675)(-3450 1675);
WIRE 16 -1 (-2900 1725)(-3450 1725);
WIRE 16 -1 (-2900 1775)(-3450 1775);
WIRE 16 -1 (-3050 2375)(-3450 2375);
WIRE 16 -1 (-3050 2425)(-3450 2425);
WIRE 16 -1 (-3050 2475)(-3450 2475);
WIRE 16 -1 (-3050 2525)(-3450 2525);
WIRE 16 -1 (-3050 2875)(-3450 2875);
WIRE 16 -1 (-3050 2925)(-3450 2925);
WIRE 16 -1 (-3050 2975)(-3450 2975);
WIRE 16 -1 (-3050 3025)(-3450 3025);
WIRE 16 -1 (-3050 3375)(-3450 3375);
WIRE 16 -1 (-3050 3425)(-3450 3425);
WIRE 16 -1 (-3050 3475)(-3450 3475);
WIRE 16 -1 (-3050 3525)(-3450 3525);
WIRE 16 -1 (-2900 2125)(-3450 2125);
WIRE 16 -1 (-2900 2175)(-3450 2175);
WIRE 16 -1 (-2900 2225)(-3450 2225);
WIRE 16 -1 (-2900 2275)(-3450 2275);
WIRE 16 -1 (-2900 2725)(-3450 2725);
WIRE 16 -1 (-2900 3125)(-3450 3125);
WIRE 16 -1 (-2900 3175)(-3450 3175);
FORCENOTE
FROM OCP
(-7250 3400) 0;
DISPLAY LEFT (-7250 3400);
DISPLAY 1.021277 (-7250 3400);
PAINT PURPLE (-7250 3400);
FORCENOTE
TO OCP
(-2700 3400) 0;
DISPLAY LEFT (-2700 3400);
DISPLAY 1.021277 (-2700 3400);
PAINT PURPLE (-2700 3400);
FORCENOTE
ROOM=CPU0
(-7950 375) 0;
DISPLAY LEFT (-7950 375);
DISPLAY 1.723404 (-7950 375);
PAINT PURPLE (-7950 375);
FORCENOTE
BOM_COST=PROC_SOCKET
(-7950 250) 0;
DISPLAY LEFT (-7950 250);
DISPLAY 1.723404 (-7950 250);
PAINT PURPLE (-7950 250);
FORCENOTE
SKYLAKE - SKT0 - 12 OF 21
(-1675 150) 0;
DISPLAY LEFT (-1675 150);
DISPLAY 1.021277 (-1675 150);
PAINT RED (-1675 150);
QUIT
